G04*
G04 #@! TF.GenerationSoftware,Altium Limited,Altium Designer,23.0.1 (38)*
G04*
G04 Layer_Color=65535*
%FSLAX25Y25*%
%MOIN*%
G70*
G04*
G04 #@! TF.SameCoordinates,C48E81DB-6E20-4E2D-80E6-7C5AFAA1A21F*
G04*
G04*
G04 #@! TF.FilePolarity,Positive*
G04*
G01*
G75*
%ADD10C,0.00984*%
%ADD11C,0.01968*%
%ADD12C,0.02000*%
%ADD13C,0.01575*%
%ADD14C,0.01000*%
%ADD15C,0.00787*%
%ADD16C,0.00394*%
%ADD17C,0.01575*%
%ADD18C,0.00300*%
%ADD19C,0.00500*%
%ADD20C,0.00600*%
%ADD21C,0.00100*%
%ADD22C,0.00591*%
%ADD23C,0.00900*%
%ADD24C,0.00800*%
%ADD25R,0.50197X0.35236*%
%ADD26R,0.17717X0.59055*%
%ADD27R,0.29528X0.28543*%
D10*
X680118Y-323228D02*
G03*
X680118Y-323228I-492J0D01*
G01*
X680118Y-315748D02*
G03*
X680118Y-315748I-492J0D01*
G01*
X676968Y-94095D02*
G03*
X676968Y-94095I-492J0D01*
G01*
X681496Y-62541D02*
G03*
X681496Y-62541I-492J0D01*
G01*
X611417Y-90158D02*
G03*
X611417Y-90158I-492J0D01*
G01*
X578543D02*
G03*
X578543Y-90158I-492J0D01*
G01*
X421614Y-141634D02*
G03*
X421614Y-141634I-492J0D01*
G01*
X410335Y-123130D02*
G03*
X410335Y-123130I-492J0D01*
G01*
X437106Y-122736D02*
G03*
X437106Y-122736I-492J0D01*
G01*
X245768Y-127461D02*
G03*
X245768Y-127461I-492J0D01*
G01*
X623721Y-233858D02*
G03*
X623721Y-233858I-492J0D01*
G01*
X685728Y-235846D02*
G03*
X685728Y-235846I-492J0D01*
G01*
X596457Y-152756D02*
G03*
X596457Y-152756I-492J0D01*
G01*
X644193Y-113583D02*
G03*
X644193Y-113583I-492J0D01*
G01*
X585335Y-169291D02*
G03*
X585335Y-169291I-492J0D01*
G01*
X612697Y-296063D02*
G03*
X612697Y-296063I-492J0D01*
G01*
X677854Y-307500D02*
G03*
X677854Y-307500I-492J0D01*
G01*
X559173Y-110433D02*
G03*
X559173Y-110433I-492J0D01*
G01*
X498327Y-133268D02*
G03*
X498327Y-133268I-492J0D01*
G01*
X607185Y-168405D02*
G03*
X607185Y-168405I-492J0D01*
G01*
X515690Y-326029D02*
G03*
X515690Y-326029I-492J0D01*
G01*
X515592Y-342171D02*
G03*
X515592Y-342171I-492J0D01*
G01*
X643209Y-320374D02*
G03*
X643209Y-320374I-492J0D01*
G01*
X661909Y-320473D02*
G03*
X661909Y-320473I-492J0D01*
G01*
X40846Y4921D02*
G03*
X40846Y4921I-492J0D01*
G01*
X33957D02*
G03*
X33957Y4921I-492J0D01*
G01*
X27067D02*
G03*
X27067Y4921I-492J0D01*
G01*
X47736D02*
G03*
X47736Y4921I-492J0D01*
G01*
X90847Y-116142D02*
G03*
X90847Y-116142I-492J0D01*
G01*
X38287Y-255795D02*
G03*
X38287Y-255795I-492J0D01*
G01*
Y-150480D02*
G03*
X38287Y-150480I-492J0D01*
G01*
Y-309929D02*
G03*
X38287Y-309929I-492J0D01*
G01*
Y-203630D02*
G03*
X38287Y-203630I-492J0D01*
G01*
X280020Y-110600D02*
G03*
X280020Y-110600I-492J0D01*
G01*
X209744Y-111053D02*
G03*
X209744Y-111053I-492J0D01*
G01*
X523524Y-121013D02*
G03*
X523524Y-121013I-492J0D01*
G01*
X464862Y-117134D02*
G03*
X464862Y-117134I-492J0D01*
G01*
D11*
X673130Y-235138D02*
G03*
X673130Y-235138I-984J0D01*
G01*
X665256Y-306791D02*
G03*
X665256Y-306791I-984J0D01*
G01*
X558957Y-123524D02*
G03*
X558957Y-123524I-984J0D01*
G01*
D12*
X656488Y-14025D02*
G03*
X656488Y-14025I-100J0D01*
G01*
X67137Y-73671D02*
G03*
X67137Y-73671I-100J0D01*
G01*
X410236Y-143701D02*
X436614D01*
X410236Y-108268D02*
X436614D01*
Y-143701D02*
Y-108268D01*
X410236Y-143701D02*
Y-108268D01*
X323622Y-141339D02*
X392913D01*
X323622Y-105512D02*
X392913D01*
Y-141339D02*
Y-105512D01*
X323622Y-141339D02*
Y-105512D01*
X426825Y-107945D02*
X440020Y-55771D01*
X422047Y-107480D02*
X440203Y-35694D01*
D13*
X470179Y-294797D02*
G03*
X470179Y-294797I-788J0D01*
G01*
X355492Y-272526D02*
G03*
X355492Y-272526I-788J0D01*
G01*
X393217Y-174277D02*
G03*
X393217Y-174277I-788J0D01*
G01*
X515383Y-195564D02*
G03*
X515383Y-195564I-788J0D01*
G01*
D14*
X288354Y-227593D02*
G03*
X288354Y-227593I-500J0D01*
G01*
D02*
G03*
X288354Y-227593I-500J0D01*
G01*
X122441Y-336614D02*
Y-136614D01*
X322441D01*
Y-336614D02*
Y-136614D01*
X122441Y-336614D02*
X322441D01*
X664695Y-106427D02*
Y18573D01*
X400207D02*
X664695D01*
X400207Y-106427D02*
Y18573D01*
Y-106427D02*
X664695D01*
X58730Y-106269D02*
Y18731D01*
Y-106269D02*
X323218D01*
Y18731D01*
X58730D02*
X323218D01*
X443126Y-65292D02*
Y-68291D01*
X445125D01*
X448124Y-65292D02*
X446125D01*
Y-68291D01*
X448124D01*
X446125Y-66792D02*
X447125D01*
X449124Y-65292D02*
Y-68291D01*
X450624D01*
X451123Y-67791D01*
Y-65792D01*
X450624Y-65292D01*
X449124D01*
X456122Y-68291D02*
X455122Y-67292D01*
Y-66292D01*
X456122Y-65292D01*
X457621D02*
Y-68291D01*
X459121D01*
X459621Y-67791D01*
Y-65792D01*
X459121Y-65292D01*
X457621D01*
X462620Y-68291D02*
X460620D01*
X462620Y-66292D01*
Y-65792D01*
X462120Y-65292D01*
X461120D01*
X460620Y-65792D01*
X465619Y-65292D02*
X463619D01*
Y-66792D01*
X464619Y-66292D01*
X465119D01*
X465619Y-66792D01*
Y-67791D01*
X465119Y-68291D01*
X464119D01*
X463619Y-67791D01*
X466618Y-68291D02*
X467618Y-67292D01*
Y-66292D01*
X466618Y-65292D01*
X473616D02*
X472616D01*
X472117Y-65792D01*
Y-67791D01*
X472616Y-68291D01*
X473616D01*
X474116Y-67791D01*
Y-65792D01*
X473616Y-65292D01*
X475616Y-68291D02*
Y-65792D01*
Y-66792D01*
X475116D01*
X476115D01*
X475616D01*
Y-65792D01*
X476115Y-65292D01*
X478115Y-68291D02*
Y-65792D01*
Y-66792D01*
X477615D01*
X478615D01*
X478115D01*
Y-65792D01*
X478615Y-65292D01*
X483613Y-68291D02*
Y-65792D01*
Y-66792D01*
X483113D01*
X484113D01*
X483613D01*
Y-65792D01*
X484113Y-65292D01*
X486112Y-68291D02*
X487112D01*
X487612Y-67791D01*
Y-66792D01*
X487112Y-66292D01*
X486112D01*
X485612Y-66792D01*
Y-67791D01*
X486112Y-68291D01*
X488611Y-66292D02*
Y-68291D01*
Y-67292D01*
X489111Y-66792D01*
X489611Y-66292D01*
X490111D01*
X494609Y-65292D02*
Y-68291D01*
X496109D01*
X496609Y-67791D01*
Y-65792D01*
X496109Y-65292D01*
X494609D01*
X497608Y-68291D02*
X498608D01*
X498108D01*
Y-66292D01*
X497608D01*
X500607Y-68291D02*
Y-65792D01*
Y-66792D01*
X500107D01*
X501107D01*
X500607D01*
Y-65792D01*
X501107Y-65292D01*
X503107Y-68291D02*
Y-65792D01*
Y-66792D01*
X502607D01*
X503606D01*
X503107D01*
Y-65792D01*
X503606Y-65292D01*
X506605Y-68291D02*
X505606D01*
X505106Y-67791D01*
Y-66792D01*
X505606Y-66292D01*
X506605D01*
X507105Y-66792D01*
Y-67292D01*
X505106D01*
X508105Y-66292D02*
Y-68291D01*
Y-67292D01*
X508605Y-66792D01*
X509105Y-66292D01*
X509605D01*
X512604Y-68291D02*
X511604D01*
X511104Y-67791D01*
Y-66792D01*
X511604Y-66292D01*
X512604D01*
X513103Y-66792D01*
Y-67292D01*
X511104D01*
X514103Y-68291D02*
Y-66292D01*
X515602D01*
X516102Y-66792D01*
Y-68291D01*
X517602Y-65792D02*
Y-66292D01*
X517102D01*
X518102D01*
X517602D01*
Y-67791D01*
X518102Y-68291D01*
X519601D02*
X520601D01*
X520101D01*
Y-66292D01*
X519601D01*
X522600D02*
X523600D01*
X524100Y-66792D01*
Y-68291D01*
X522600D01*
X522100Y-67791D01*
X522600Y-67292D01*
X524100D01*
X525099Y-68291D02*
X526099D01*
X525599D01*
Y-65292D01*
X525099D01*
X530598Y-68291D02*
Y-65292D01*
X532097D01*
X532597Y-65792D01*
Y-66792D01*
X532097Y-67292D01*
X530598D01*
X533597Y-68291D02*
Y-65292D01*
X535096D01*
X535596Y-65792D01*
Y-66792D01*
X535096Y-67292D01*
X533597D01*
X538595Y-65792D02*
X538095Y-65292D01*
X537096D01*
X536596Y-65792D01*
Y-66292D01*
X537096Y-66792D01*
X538095D01*
X538595Y-67292D01*
Y-67791D01*
X538095Y-68291D01*
X537096D01*
X536596Y-67791D01*
X543594Y-68291D02*
X542594Y-67292D01*
Y-66292D01*
X543594Y-65292D01*
X547092Y-65792D02*
X546593Y-65292D01*
X545593D01*
X545093Y-65792D01*
Y-66292D01*
X545593Y-66792D01*
X546593D01*
X547092Y-67292D01*
Y-67791D01*
X546593Y-68291D01*
X545593D01*
X545093Y-67791D01*
X548092Y-68291D02*
Y-66292D01*
X549092Y-65292D01*
X550091Y-66292D01*
Y-68291D01*
Y-66792D01*
X548092D01*
X553090Y-65292D02*
X551091D01*
Y-66792D01*
X552091Y-66292D01*
X552591D01*
X553090Y-66792D01*
Y-67791D01*
X552591Y-68291D01*
X551591D01*
X551091Y-67791D01*
X554090Y-65792D02*
X554590Y-65292D01*
X555590D01*
X556089Y-65792D01*
Y-66292D01*
X555590Y-66792D01*
X555090D01*
X555590D01*
X556089Y-67292D01*
Y-67791D01*
X555590Y-68291D01*
X554590D01*
X554090Y-67791D01*
X557089Y-68291D02*
X558089Y-67292D01*
Y-66292D01*
X557089Y-65292D01*
X442909Y-59881D02*
Y-62880D01*
X444909D01*
X447908Y-59881D02*
X445908D01*
Y-62880D01*
X447908D01*
X445908Y-61380D02*
X446908D01*
X448908Y-59881D02*
Y-62880D01*
X450407D01*
X450907Y-62380D01*
Y-60381D01*
X450407Y-59881D01*
X448908D01*
X455905Y-62880D02*
X454906Y-61880D01*
Y-60881D01*
X455905Y-59881D01*
X457405D02*
Y-62880D01*
X458904D01*
X459404Y-62380D01*
Y-60381D01*
X458904Y-59881D01*
X457405D01*
X462403Y-62880D02*
X460404D01*
X462403Y-60881D01*
Y-60381D01*
X461903Y-59881D01*
X460904D01*
X460404Y-60381D01*
X464902Y-62880D02*
Y-59881D01*
X463403Y-61380D01*
X465402D01*
X466402Y-62880D02*
X467402Y-61880D01*
Y-60881D01*
X466402Y-59881D01*
X473400D02*
X472400D01*
X471900Y-60381D01*
Y-62380D01*
X472400Y-62880D01*
X473400D01*
X473900Y-62380D01*
Y-60381D01*
X473400Y-59881D01*
X474899Y-62880D02*
Y-60881D01*
X476399D01*
X476898Y-61380D01*
Y-62880D01*
X481397D02*
Y-60381D01*
Y-61380D01*
X480897D01*
X481897D01*
X481397D01*
Y-60381D01*
X481897Y-59881D01*
X483896Y-62880D02*
X484896D01*
X485396Y-62380D01*
Y-61380D01*
X484896Y-60881D01*
X483896D01*
X483396Y-61380D01*
Y-62380D01*
X483896Y-62880D01*
X486395Y-60881D02*
Y-62880D01*
Y-61880D01*
X486895Y-61380D01*
X487395Y-60881D01*
X487895D01*
X494393Y-60381D02*
X493893Y-59881D01*
X492893D01*
X492393Y-60381D01*
Y-60881D01*
X492893Y-61380D01*
X493893D01*
X494393Y-61880D01*
Y-62380D01*
X493893Y-62880D01*
X492893D01*
X492393Y-62380D01*
X495393Y-62880D02*
X496392D01*
X495892D01*
Y-60881D01*
X495393D01*
X497892Y-62880D02*
Y-60881D01*
X499391D01*
X499891Y-61380D01*
Y-62880D01*
X501890Y-63880D02*
X502390D01*
X502890Y-63380D01*
Y-60881D01*
X501391D01*
X500891Y-61380D01*
Y-62380D01*
X501391Y-62880D01*
X502890D01*
X503890D02*
X504889D01*
X504390D01*
Y-59881D01*
X503890D01*
X507889Y-62880D02*
X506889D01*
X506389Y-62380D01*
Y-61380D01*
X506889Y-60881D01*
X507889D01*
X508388Y-61380D01*
Y-61880D01*
X506389D01*
X514386Y-59881D02*
X512387D01*
Y-62880D01*
X514386D01*
X512387Y-61380D02*
X513387D01*
X515386Y-62880D02*
Y-60881D01*
X516886D01*
X517385Y-61380D01*
Y-62880D01*
X520384Y-59881D02*
Y-62880D01*
X518885D01*
X518385Y-62380D01*
Y-61380D01*
X518885Y-60881D01*
X520384D01*
X522884Y-62880D02*
X521884D01*
X521384Y-62380D01*
Y-61380D01*
X521884Y-60881D01*
X522884D01*
X523383Y-61380D01*
Y-61880D01*
X521384D01*
X526382Y-59881D02*
Y-62880D01*
X524883D01*
X524383Y-62380D01*
Y-61380D01*
X524883Y-60881D01*
X526382D01*
X530381Y-62880D02*
Y-59881D01*
X531881D01*
X532380Y-60381D01*
Y-61380D01*
X531881Y-61880D01*
X530381D01*
X533380Y-62880D02*
Y-59881D01*
X534880D01*
X535380Y-60381D01*
Y-61380D01*
X534880Y-61880D01*
X533380D01*
X538379Y-60381D02*
X537879Y-59881D01*
X536879D01*
X536379Y-60381D01*
Y-60881D01*
X536879Y-61380D01*
X537879D01*
X538379Y-61880D01*
Y-62380D01*
X537879Y-62880D01*
X536879D01*
X536379Y-62380D01*
X543377Y-62880D02*
X542377Y-61880D01*
Y-60881D01*
X543377Y-59881D01*
X544876Y-62880D02*
Y-59881D01*
X545876Y-60881D01*
X546876Y-59881D01*
Y-62880D01*
X548375D02*
X549375D01*
X549875Y-62380D01*
Y-61380D01*
X549375Y-60881D01*
X548375D01*
X547875Y-61380D01*
Y-62380D01*
X548375Y-62880D01*
X550875D02*
X552374D01*
X552874Y-62380D01*
X552374Y-61880D01*
X551374D01*
X550875Y-61380D01*
X551374Y-60881D01*
X552874D01*
X554373Y-60381D02*
Y-60881D01*
X553874D01*
X554873D01*
X554373D01*
Y-62380D01*
X554873Y-62880D01*
X561371Y-60881D02*
X559872D01*
X559372Y-61380D01*
Y-62380D01*
X559872Y-62880D01*
X561371D01*
X562871D02*
X563870D01*
X564370Y-62380D01*
Y-61380D01*
X563870Y-60881D01*
X562871D01*
X562371Y-61380D01*
Y-62380D01*
X562871Y-62880D01*
X565370D02*
Y-60881D01*
X565870D01*
X566369Y-61380D01*
Y-62880D01*
Y-61380D01*
X566869Y-60881D01*
X567369Y-61380D01*
Y-62880D01*
X568369D02*
Y-60881D01*
X568869D01*
X569369Y-61380D01*
Y-62880D01*
Y-61380D01*
X569868Y-60881D01*
X570368Y-61380D01*
Y-62880D01*
X571868D02*
X572867D01*
X573367Y-62380D01*
Y-61380D01*
X572867Y-60881D01*
X571868D01*
X571368Y-61380D01*
Y-62380D01*
X571868Y-62880D01*
X574367D02*
Y-60881D01*
X575867D01*
X576366Y-61380D01*
Y-62880D01*
X577366D02*
X578366Y-61880D01*
Y-60881D01*
X577366Y-59881D01*
X443126Y-58449D02*
Y-52451D01*
X446125D01*
X447125Y-53450D01*
Y-55450D01*
X446125Y-56450D01*
X443126D01*
X449124Y-58449D02*
Y-52451D01*
X452123D01*
X453123Y-53450D01*
Y-55450D01*
X452123Y-56450D01*
X449124D01*
X459121Y-53450D02*
X458121Y-52451D01*
X456122D01*
X455122Y-53450D01*
Y-54450D01*
X456122Y-55450D01*
X458121D01*
X459121Y-56450D01*
Y-57449D01*
X458121Y-58449D01*
X456122D01*
X455122Y-57449D01*
X471117Y-53450D02*
X470117Y-52451D01*
X468118D01*
X467118Y-53450D01*
Y-54450D01*
X468118Y-55450D01*
X470117D01*
X471117Y-56450D01*
Y-57449D01*
X470117Y-58449D01*
X468118D01*
X467118Y-57449D01*
X476115Y-58449D02*
X474116D01*
X473116Y-57449D01*
Y-55450D01*
X474116Y-54450D01*
X476115D01*
X477115Y-55450D01*
Y-56450D01*
X473116D01*
X479114Y-58449D02*
X481114D01*
X480114D01*
Y-52451D01*
X479114D01*
X487112Y-58449D02*
X485112D01*
X484113Y-57449D01*
Y-55450D01*
X485112Y-54450D01*
X487112D01*
X488111Y-55450D01*
Y-56450D01*
X484113D01*
X494109Y-54450D02*
X491111D01*
X490111Y-55450D01*
Y-57449D01*
X491111Y-58449D01*
X494109D01*
X497109Y-53450D02*
Y-54450D01*
X496109D01*
X498108D01*
X497109D01*
Y-57449D01*
X498108Y-58449D01*
X442339Y-34190D02*
Y-37189D01*
X444338D01*
X447337Y-34190D02*
X445338D01*
Y-37189D01*
X447337D01*
X445338Y-35689D02*
X446337D01*
X448337Y-34190D02*
Y-37189D01*
X449836D01*
X450336Y-36689D01*
Y-34690D01*
X449836Y-34190D01*
X448337D01*
X455334Y-37189D02*
X454335Y-36189D01*
Y-35190D01*
X455334Y-34190D01*
X456834D02*
Y-37189D01*
X458333D01*
X458833Y-36689D01*
Y-34690D01*
X458333Y-34190D01*
X456834D01*
X461832Y-37189D02*
X459833D01*
X461832Y-35190D01*
Y-34690D01*
X461332Y-34190D01*
X460333D01*
X459833Y-34690D01*
X464831Y-34190D02*
X462832D01*
Y-35689D01*
X463832Y-35190D01*
X464331D01*
X464831Y-35689D01*
Y-36689D01*
X464331Y-37189D01*
X463332D01*
X462832Y-36689D01*
X465831Y-37189D02*
X466831Y-36189D01*
Y-35190D01*
X465831Y-34190D01*
X472829D02*
X471829D01*
X471329Y-34690D01*
Y-36689D01*
X471829Y-37189D01*
X472829D01*
X473328Y-36689D01*
Y-34690D01*
X472829Y-34190D01*
X474828Y-37189D02*
Y-34690D01*
Y-35689D01*
X474328D01*
X475328D01*
X474828D01*
Y-34690D01*
X475328Y-34190D01*
X477327Y-37189D02*
Y-34690D01*
Y-35689D01*
X476827D01*
X477827D01*
X477327D01*
Y-34690D01*
X477827Y-34190D01*
X482826Y-37189D02*
Y-34690D01*
Y-35689D01*
X482326D01*
X483325D01*
X482826D01*
Y-34690D01*
X483325Y-34190D01*
X485325Y-37189D02*
X486324D01*
X486824Y-36689D01*
Y-35689D01*
X486324Y-35190D01*
X485325D01*
X484825Y-35689D01*
Y-36689D01*
X485325Y-37189D01*
X487824Y-35190D02*
Y-37189D01*
Y-36189D01*
X488324Y-35689D01*
X488824Y-35190D01*
X489323D01*
X493822Y-34190D02*
Y-36689D01*
X494322Y-37189D01*
X495321D01*
X495821Y-36689D01*
Y-34190D01*
X498820Y-34690D02*
X498320Y-34190D01*
X497321D01*
X496821Y-34690D01*
Y-35190D01*
X497321Y-35689D01*
X498320D01*
X498820Y-36189D01*
Y-36689D01*
X498320Y-37189D01*
X497321D01*
X496821Y-36689D01*
X499820Y-34190D02*
Y-37189D01*
X501320D01*
X501819Y-36689D01*
Y-36189D01*
X501320Y-35689D01*
X499820D01*
X501320D01*
X501819Y-35190D01*
Y-34690D01*
X501320Y-34190D01*
X499820D01*
X507817D02*
X505818D01*
Y-35689D01*
X506818D01*
X505818D01*
Y-37189D01*
X508817Y-34190D02*
X510816D01*
X509817D01*
Y-37189D01*
X511816Y-34190D02*
Y-37189D01*
X513316D01*
X513815Y-36689D01*
Y-34690D01*
X513316Y-34190D01*
X511816D01*
X514815D02*
X515815D01*
X515315D01*
Y-37189D01*
X514815D01*
X515815D01*
X521813D02*
X520313Y-35689D01*
X521813Y-34190D01*
X523312Y-35689D02*
X525312D01*
X526311Y-37189D02*
X527811Y-35689D01*
X526311Y-34190D01*
X533809D02*
X531810D01*
Y-35689D01*
X532809D01*
X531810D01*
Y-37189D01*
X534809D02*
Y-34190D01*
X536308D01*
X536808Y-34690D01*
Y-35689D01*
X536308Y-36189D01*
X534809D01*
X539807Y-34690D02*
X539307Y-34190D01*
X538308D01*
X537808Y-34690D01*
Y-36689D01*
X538308Y-37189D01*
X539307D01*
X539807Y-36689D01*
Y-35689D01*
X538807D01*
X540807Y-37189D02*
Y-35190D01*
X541806Y-34190D01*
X542806Y-35190D01*
Y-37189D01*
Y-35689D01*
X540807D01*
X546805Y-37189D02*
X548804Y-35190D01*
X554802Y-34190D02*
X552803D01*
Y-35689D01*
X553802D01*
X552803D01*
Y-37189D01*
X555802D02*
Y-34190D01*
X557301D01*
X557801Y-34690D01*
Y-35689D01*
X557301Y-36189D01*
X555802D01*
X560800Y-34690D02*
X560300Y-34190D01*
X559301D01*
X558801Y-34690D01*
Y-36689D01*
X559301Y-37189D01*
X560300D01*
X560800Y-36689D01*
Y-35689D01*
X559801D01*
X561800Y-37189D02*
Y-35190D01*
X562800Y-34190D01*
X563799Y-35190D01*
Y-37189D01*
Y-35689D01*
X561800D01*
X569298Y-37189D02*
X567798Y-35689D01*
X569298Y-34190D01*
X570797Y-35689D02*
X572796D01*
X573796Y-37189D02*
X575296Y-35689D01*
X573796Y-34190D01*
X581294Y-34690D02*
X580794Y-34190D01*
X579794D01*
X579294Y-34690D01*
Y-36689D01*
X579794Y-37189D01*
X580794D01*
X581294Y-36689D01*
Y-35689D01*
X580294D01*
X582293Y-37189D02*
Y-34190D01*
X583793D01*
X584293Y-34690D01*
Y-35689D01*
X583793Y-36189D01*
X582293D01*
X587292Y-34690D02*
X586792Y-34190D01*
X585792D01*
X585292Y-34690D01*
Y-35190D01*
X585792Y-35689D01*
X586792D01*
X587292Y-36189D01*
Y-36689D01*
X586792Y-37189D01*
X585792D01*
X585292Y-36689D01*
X590291Y-37189D02*
X588291D01*
X590291Y-35190D01*
Y-34690D01*
X589791Y-34190D01*
X588791D01*
X588291Y-34690D01*
X595289Y-37189D02*
X594289Y-36189D01*
Y-35190D01*
X595289Y-34190D01*
X596789Y-37189D02*
Y-34190D01*
X598788Y-37189D01*
Y-34190D01*
X600287Y-37189D02*
X601287D01*
X601787Y-36689D01*
Y-35689D01*
X601287Y-35190D01*
X600287D01*
X599788Y-35689D01*
Y-36689D01*
X600287Y-37189D01*
X602787Y-35190D02*
Y-37189D01*
Y-36189D01*
X603287Y-35689D01*
X603786Y-35190D01*
X604286D01*
X605786Y-37189D02*
Y-35190D01*
X606285D01*
X606785Y-35689D01*
Y-37189D01*
Y-35689D01*
X607285Y-35190D01*
X607785Y-35689D01*
Y-37189D01*
X609285Y-35190D02*
X610284D01*
X610784Y-35689D01*
Y-37189D01*
X609285D01*
X608785Y-36689D01*
X609285Y-36189D01*
X610784D01*
X611784Y-37189D02*
X612783D01*
X612284D01*
Y-34190D01*
X611784D01*
X614283Y-37189D02*
X615283Y-36189D01*
Y-35190D01*
X614283Y-34190D01*
X442339Y-39096D02*
Y-42095D01*
X444338D01*
X447337Y-39096D02*
X445338D01*
Y-42095D01*
X447337D01*
X445338Y-40595D02*
X446337D01*
X448337Y-39096D02*
Y-42095D01*
X449836D01*
X450336Y-41595D01*
Y-39596D01*
X449836Y-39096D01*
X448337D01*
X455334Y-42095D02*
X454335Y-41095D01*
Y-40095D01*
X455334Y-39096D01*
X456834D02*
Y-42095D01*
X458333D01*
X458833Y-41595D01*
Y-39596D01*
X458333Y-39096D01*
X456834D01*
X461832Y-42095D02*
X459833D01*
X461832Y-40095D01*
Y-39596D01*
X461332Y-39096D01*
X460333D01*
X459833Y-39596D01*
X464831Y-39096D02*
X462832D01*
Y-40595D01*
X463832Y-40095D01*
X464331D01*
X464831Y-40595D01*
Y-41595D01*
X464331Y-42095D01*
X463332D01*
X462832Y-41595D01*
X465831Y-42095D02*
X466831Y-41095D01*
Y-40095D01*
X465831Y-39096D01*
X471329D02*
Y-42095D01*
X473328D01*
X474328D02*
X475328D01*
X474828D01*
Y-40095D01*
X474328D01*
X477327Y-39596D02*
Y-40095D01*
X476827D01*
X477827D01*
X477327D01*
Y-41595D01*
X477827Y-42095D01*
X482826D02*
Y-39596D01*
Y-40595D01*
X482326D01*
X483325D01*
X482826D01*
Y-39596D01*
X483325Y-39096D01*
X485325Y-42095D02*
X486324D01*
X486824Y-41595D01*
Y-40595D01*
X486324Y-40095D01*
X485325D01*
X484825Y-40595D01*
Y-41595D01*
X485325Y-42095D01*
X487824Y-40095D02*
Y-42095D01*
Y-41095D01*
X488324Y-40595D01*
X488824Y-40095D01*
X489323D01*
X493822Y-39096D02*
Y-41595D01*
X494322Y-42095D01*
X495321D01*
X495821Y-41595D01*
Y-39096D01*
X498820Y-39596D02*
X498320Y-39096D01*
X497321D01*
X496821Y-39596D01*
Y-40095D01*
X497321Y-40595D01*
X498320D01*
X498820Y-41095D01*
Y-41595D01*
X498320Y-42095D01*
X497321D01*
X496821Y-41595D01*
X499820Y-39096D02*
Y-42095D01*
X501320D01*
X501819Y-41595D01*
Y-41095D01*
X501320Y-40595D01*
X499820D01*
X501320D01*
X501819Y-40095D01*
Y-39596D01*
X501320Y-39096D01*
X499820D01*
X507817D02*
X505818D01*
Y-40595D01*
X506818D01*
X505818D01*
Y-42095D01*
X508817Y-39096D02*
X510816D01*
X509817D01*
Y-42095D01*
X511816Y-39096D02*
Y-42095D01*
X513316D01*
X513815Y-41595D01*
Y-39596D01*
X513316Y-39096D01*
X511816D01*
X514815D02*
X515815D01*
X515315D01*
Y-42095D01*
X514815D01*
X515815D01*
X521813D02*
X520313Y-40595D01*
X521813Y-39096D01*
X523312Y-40595D02*
X525312D01*
X526311Y-42095D02*
X527811Y-40595D01*
X526311Y-39096D01*
X533809Y-39596D02*
X533309Y-39096D01*
X532309D01*
X531810Y-39596D01*
Y-41595D01*
X532309Y-42095D01*
X533309D01*
X533809Y-41595D01*
Y-40595D01*
X532809D01*
X534809Y-42095D02*
Y-39096D01*
X536308D01*
X536808Y-39596D01*
Y-40595D01*
X536308Y-41095D01*
X534809D01*
X539807Y-39596D02*
X539307Y-39096D01*
X538308D01*
X537808Y-39596D01*
Y-40095D01*
X538308Y-40595D01*
X539307D01*
X539807Y-41095D01*
Y-41595D01*
X539307Y-42095D01*
X538308D01*
X537808Y-41595D01*
X542806Y-42095D02*
X540807D01*
X542806Y-40095D01*
Y-39596D01*
X542306Y-39096D01*
X541307D01*
X540807Y-39596D01*
X547804Y-42095D02*
X546805Y-41095D01*
Y-40095D01*
X547804Y-39096D01*
X549304D02*
Y-42095D01*
X550804D01*
X551303Y-41595D01*
Y-39596D01*
X550804Y-39096D01*
X549304D01*
X553802Y-42095D02*
X552803D01*
X552303Y-41595D01*
Y-40595D01*
X552803Y-40095D01*
X553802D01*
X554302Y-40595D01*
Y-41095D01*
X552303D01*
X555302Y-39096D02*
Y-42095D01*
X556802D01*
X557301Y-41595D01*
Y-41095D01*
Y-40595D01*
X556802Y-40095D01*
X555302D01*
X558301D02*
Y-41595D01*
X558801Y-42095D01*
X560300D01*
Y-40095D01*
X562300Y-43095D02*
X562800D01*
X563299Y-42595D01*
Y-40095D01*
X561800D01*
X561300Y-40595D01*
Y-41595D01*
X561800Y-42095D01*
X563299D01*
X564299D02*
X566298Y-40095D01*
X567298Y-42095D02*
Y-39096D01*
X568798D01*
X569298Y-39596D01*
Y-40595D01*
X568798Y-41095D01*
X567298D01*
X570297Y-40095D02*
Y-42095D01*
Y-41095D01*
X570797Y-40595D01*
X571297Y-40095D01*
X571797D01*
X573796Y-42095D02*
X574796D01*
X575296Y-41595D01*
Y-40595D01*
X574796Y-40095D01*
X573796D01*
X573296Y-40595D01*
Y-41595D01*
X573796Y-42095D01*
X577295Y-43095D02*
X577795D01*
X578295Y-42595D01*
Y-40095D01*
X576795D01*
X576295Y-40595D01*
Y-41595D01*
X576795Y-42095D01*
X578295D01*
X579294D02*
X580294Y-41095D01*
Y-40095D01*
X579294Y-39096D01*
X441551Y-26467D02*
Y-31465D01*
X442551Y-32465D01*
X444550D01*
X445550Y-31465D01*
Y-26467D01*
X447549Y-32465D02*
Y-28466D01*
X449549Y-26467D01*
X451548Y-28466D01*
Y-32465D01*
Y-29465D01*
X447549D01*
X453547Y-32465D02*
Y-26467D01*
X456546D01*
X457546Y-27466D01*
Y-29465D01*
X456546Y-30465D01*
X453547D01*
X455547D02*
X457546Y-32465D01*
X459545Y-26467D02*
X463544D01*
X461545D01*
Y-32465D01*
X475540Y-27466D02*
X474541Y-26467D01*
X472541D01*
X471542Y-27466D01*
Y-28466D01*
X472541Y-29465D01*
X474541D01*
X475540Y-30465D01*
Y-31465D01*
X474541Y-32465D01*
X472541D01*
X471542Y-31465D01*
X480539Y-32465D02*
X478539D01*
X477539Y-31465D01*
Y-29465D01*
X478539Y-28466D01*
X480539D01*
X481538Y-29465D01*
Y-30465D01*
X477539D01*
X483538Y-32465D02*
X485537D01*
X484537D01*
Y-26467D01*
X483538D01*
X491535Y-32465D02*
X489536D01*
X488536Y-31465D01*
Y-29465D01*
X489536Y-28466D01*
X491535D01*
X492535Y-29465D01*
Y-30465D01*
X488536D01*
X498533Y-28466D02*
X495534D01*
X494534Y-29465D01*
Y-31465D01*
X495534Y-32465D01*
X498533D01*
X501532Y-27466D02*
Y-28466D01*
X500532D01*
X502531D01*
X501532D01*
Y-31465D01*
X502531Y-32465D01*
D15*
X561791Y-352539D02*
G03*
X561791Y-352539I-2500J0D01*
G01*
X31216Y-189189D02*
G03*
X31216Y-189189I-1000J0D01*
G01*
Y-296866D02*
G03*
X31216Y-296866I-1000J0D01*
G01*
X683323Y-29610D02*
Y-25476D01*
X688386Y-29626D02*
Y-25492D01*
X550394Y-235827D02*
X580315D01*
Y-253937D02*
Y-250945D01*
Y-238819D02*
Y-235827D01*
X550394Y-253937D02*
X580315D01*
X550394D02*
Y-250945D01*
Y-238819D02*
Y-235827D01*
X583858Y-246063D02*
Y-243701D01*
X582677Y-244882D02*
X585039D01*
X599756Y-262748D02*
X626228D01*
Y-289220D02*
Y-284211D01*
Y-267758D02*
Y-262748D01*
X599756Y-289220D02*
X626228D01*
X599756D02*
Y-284211D01*
Y-267758D02*
Y-262748D01*
X682928Y-319542D02*
X689513D01*
X682928Y-325340D02*
X689513D01*
X669685Y-326181D02*
X675984D01*
X669766Y-320354D02*
X676066D01*
X669685Y-318701D02*
X675984D01*
X669766Y-312874D02*
X676066D01*
X682928Y-312849D02*
X689513D01*
X682928Y-318647D02*
X689513D01*
X679823Y-108169D02*
X683957D01*
X679823Y-69784D02*
X683957D01*
X679823Y-70965D02*
Y-69784D01*
Y-81496D02*
Y-78642D01*
Y-99311D02*
Y-96457D01*
Y-108169D02*
Y-106988D01*
X691831Y-59055D02*
Y-47244D01*
X679035Y-59055D02*
Y-47244D01*
X676099Y-109563D02*
Y-98311D01*
X668783Y-109563D02*
Y-98311D01*
X661668Y-113287D02*
X666678D01*
X661668Y-107972D02*
X666678D01*
X691118Y-63386D02*
X696284D01*
X691118Y-68898D02*
X696284D01*
X667639Y-91808D02*
X671773D01*
X667618Y-97146D02*
X671752D01*
X682207Y-33978D02*
Y-29844D01*
X676870Y-33957D02*
Y-29823D01*
X683858Y-40378D02*
Y-35212D01*
X689370Y-40378D02*
Y-35212D01*
X691339Y-40514D02*
Y-35348D01*
X696850Y-40514D02*
Y-35348D01*
X613583Y-99311D02*
X620669D01*
X613583Y-87303D02*
X620669D01*
X624976Y-90551D02*
X630142D01*
X624976Y-96063D02*
X630142D01*
X580709Y-99311D02*
X587795D01*
X580709Y-87303D02*
X587795D01*
X594488Y-94709D02*
Y-89543D01*
X600000Y-94709D02*
Y-89543D01*
X415807Y-134055D02*
Y-115551D01*
X429095Y-134055D02*
X431437D01*
X415807D02*
X418150D01*
X431437D02*
Y-115551D01*
X429095D02*
X431437D01*
X415807D02*
X418150D01*
X406968Y-132990D02*
Y-126690D01*
X412795Y-133071D02*
Y-126772D01*
X433740Y-132596D02*
Y-126297D01*
X439567Y-132677D02*
Y-126378D01*
X254429Y-124803D02*
Y-117717D01*
X242421Y-124803D02*
Y-117717D01*
X247638Y-113213D02*
Y-108047D01*
X253150Y-113213D02*
Y-108047D01*
X412629Y-121079D02*
Y-114495D01*
X406832Y-121079D02*
Y-114495D01*
X439513Y-122181D02*
Y-115597D01*
X433716Y-122181D02*
Y-115597D01*
X547417Y-277165D02*
X552583D01*
X547417Y-282677D02*
X552583D01*
X603299Y-207522D02*
Y-202512D01*
Y-228984D02*
Y-223974D01*
Y-228984D02*
X629772D01*
Y-207522D02*
Y-202512D01*
Y-228984D02*
Y-223974D01*
X603299Y-202512D02*
X629772D01*
X660236Y-203150D02*
Y-200787D01*
X659055Y-201969D02*
X661417D01*
X666299Y-168504D02*
X669291D01*
X651181D02*
X654173D01*
X651181Y-198425D02*
Y-168504D01*
X666299Y-198425D02*
X669291D01*
X651181D02*
X654173D01*
X669291D02*
Y-168504D01*
X680463Y-188472D02*
Y-181887D01*
X686260Y-188472D02*
Y-181887D01*
X637697Y-206693D02*
Y-205118D01*
X644193Y-206693D02*
Y-205118D01*
X627165Y-231496D02*
Y-231102D01*
Y-236614D02*
Y-236221D01*
Y-236614D02*
X634252D01*
Y-231496D02*
Y-231102D01*
Y-236614D02*
Y-236221D01*
X627165Y-231102D02*
X634252D01*
X647146Y-228346D02*
Y-221260D01*
X653642Y-228346D02*
Y-221260D01*
X558125Y-224552D02*
X564710D01*
X558125Y-218755D02*
X564710D01*
X588834Y-240059D02*
X593844D01*
X588834Y-234744D02*
X593844D01*
X595866Y-243110D02*
Y-236417D01*
X602559Y-243110D02*
Y-236417D01*
X613583Y-230118D02*
X620276D01*
X613583Y-236811D02*
X620276D01*
X684646Y-209805D02*
Y-204639D01*
X679134Y-209805D02*
Y-204639D01*
X679134Y-187500D02*
Y-181791D01*
X672047Y-187500D02*
Y-181791D01*
X669828Y-210773D02*
Y-204188D01*
X664031Y-210773D02*
Y-204188D01*
X675197Y-238189D02*
Y-218504D01*
X663386D02*
X675197D01*
X663386Y-238189D02*
Y-218504D01*
Y-238189D02*
X675197D01*
X597638Y-191339D02*
X600000D01*
X598819Y-192520D02*
Y-190157D01*
X632283Y-200394D02*
Y-197402D01*
Y-185276D02*
Y-182283D01*
X602362D02*
X632283D01*
X602362Y-200394D02*
Y-197402D01*
Y-185276D02*
Y-182283D01*
Y-200394D02*
X632283D01*
X592520Y-190151D02*
Y-187014D01*
X599606Y-190151D02*
Y-187014D01*
X671161Y-211024D02*
Y-203937D01*
X677658Y-211024D02*
Y-203937D01*
X583071Y-190151D02*
Y-187014D01*
X590158Y-190151D02*
Y-187014D01*
X557556Y-201652D02*
Y-197518D01*
X562894Y-201673D02*
Y-197539D01*
X550645Y-226521D02*
Y-219936D01*
X556442Y-226521D02*
Y-219936D01*
X559842Y-217150D02*
Y-211984D01*
X565354Y-217150D02*
Y-211984D01*
X583760Y-148327D02*
Y-120177D01*
X604035D02*
X608366D01*
X583760D02*
X588091D01*
X608366Y-148327D02*
Y-120177D01*
X604035Y-148327D02*
X608366D01*
X583760D02*
X588091D01*
X648401Y-155445D02*
Y-150835D01*
Y-137055D02*
Y-134335D01*
Y-120555D02*
Y-115945D01*
X699901D01*
Y-155445D02*
Y-115945D01*
X648401Y-155445D02*
X699901D01*
X578957Y-181535D02*
Y-177264D01*
Y-161319D02*
Y-157047D01*
X550965D02*
X578957D01*
X550965Y-181535D02*
Y-177264D01*
Y-161319D02*
Y-157047D01*
Y-181535D02*
X578957D01*
X616142Y-293701D02*
Y-293307D01*
Y-298819D02*
Y-298425D01*
Y-298819D02*
X623228D01*
Y-293701D02*
Y-293307D01*
Y-298819D02*
Y-298425D01*
X616142Y-293307D02*
X623228D01*
X597047Y-292323D02*
X603740D01*
X597047Y-299016D02*
X603740D01*
X638583Y-266043D02*
X640158D01*
X638583Y-272539D02*
X640158D01*
X556682Y-295418D02*
X563266D01*
X556682Y-289621D02*
X563266D01*
X546708Y-294631D02*
X553292D01*
X546708Y-288834D02*
X553292D01*
X594390Y-293843D02*
Y-288834D01*
X589075Y-293843D02*
Y-288834D01*
X545155Y-261692D02*
Y-257558D01*
X550492Y-261713D02*
Y-257579D01*
X569095Y-288386D02*
X575787D01*
X569095Y-295079D02*
X575787D01*
X590945Y-255112D02*
Y-251975D01*
X598032Y-255112D02*
Y-251975D01*
X601968Y-255506D02*
Y-252368D01*
X609055Y-255506D02*
Y-252368D01*
X661319Y-272047D02*
X667028D01*
X661319Y-264961D02*
X667028D01*
X639149Y-280709D02*
X644315D01*
X639149Y-275197D02*
X644315D01*
X661275Y-273479D02*
X667859D01*
X661275Y-279276D02*
X667859D01*
X662088Y-249404D02*
X668672D01*
X662088Y-255201D02*
X668672D01*
X661811Y-263484D02*
X668898D01*
X661811Y-256988D02*
X668898D01*
X660630Y-254331D02*
X662992D01*
X661811Y-255512D02*
Y-253150D01*
X628346Y-248268D02*
Y-245276D01*
Y-263386D02*
Y-260394D01*
Y-263386D02*
X658268D01*
Y-248268D02*
Y-245276D01*
Y-263386D02*
Y-260394D01*
X628346Y-245276D02*
X658268D01*
X667323Y-309842D02*
Y-290158D01*
X655512D02*
X667323D01*
X655512Y-309842D02*
Y-290158D01*
Y-309842D02*
X667323D01*
X640059Y-298425D02*
Y-291339D01*
X646555Y-298425D02*
Y-291339D01*
X541339Y-120472D02*
X561024D01*
X541339Y-132283D02*
Y-120472D01*
Y-132283D02*
X561024D01*
Y-120472D01*
X573524Y-146063D02*
Y-144488D01*
X580020Y-146063D02*
Y-144488D01*
X531102Y-130610D02*
X538189D01*
X531102Y-137106D02*
X538189D01*
X496314Y-107185D02*
X501324D01*
X496314Y-112500D02*
X501324D01*
X478543Y-113583D02*
X499409D01*
X478543Y-131299D02*
X499409D01*
X50098Y-39862D02*
Y-38878D01*
X44390Y-39862D02*
Y-38878D01*
X127264Y-41437D02*
Y-40453D01*
X121555Y-41437D02*
Y-40453D01*
X667224Y-59547D02*
X668209D01*
X667224Y-53839D02*
X668209D01*
X605020Y-51083D02*
X606004D01*
X605020Y-56791D02*
X606004D01*
X135748Y-125079D02*
Y-115079D01*
X187244D01*
Y-125079D02*
Y-115079D01*
X135748Y-125079D02*
X187244D01*
X363922Y-115945D02*
X366678D01*
X363922Y-109252D02*
X366678D01*
X363922Y-132874D02*
X366678D01*
X363922Y-139567D02*
X366678D01*
X593898Y-171063D02*
X596654D01*
X593898Y-164370D02*
X596654D01*
X611122Y-160531D02*
Y-156201D01*
Y-180807D02*
Y-176476D01*
Y-180807D02*
X639272D01*
Y-160531D02*
Y-156201D01*
Y-180807D02*
Y-176476D01*
X611122Y-156201D02*
X639272D01*
X363922Y-121457D02*
X366678D01*
X363922Y-128150D02*
X366678D01*
X549291Y-348287D02*
X565413D01*
X613169D02*
X629291D01*
X613169Y-311791D02*
X629291D01*
X549291D02*
X565413D01*
X629291Y-348287D02*
Y-311791D01*
X549291Y-348287D02*
Y-311791D01*
X-13898Y-330561D02*
X-3032D01*
X-22244Y-322214D02*
Y-311348D01*
X5315Y-322214D02*
Y-311348D01*
X-13898Y-303002D02*
X-3032D01*
X-13898Y-277410D02*
X-3032D01*
X-22244Y-269063D02*
Y-258197D01*
X5315Y-269063D02*
Y-258197D01*
X-13898Y-249850D02*
X-3032D01*
X-13898Y-224260D02*
X-3032D01*
X-22244Y-215913D02*
Y-205047D01*
X5315Y-215913D02*
Y-205047D01*
X-13898Y-196701D02*
X-3032D01*
X-13898Y-171112D02*
X-3032D01*
X-22244Y-162765D02*
Y-151899D01*
X5315Y-162765D02*
Y-151899D01*
X-13898Y-143553D02*
X-3032D01*
X518348Y-327407D02*
X522285D01*
Y-329179D02*
Y-327407D01*
X518348Y-336069D02*
X522285D01*
Y-334297D01*
X518249Y-343549D02*
X522186D01*
Y-345321D02*
Y-343549D01*
X518249Y-352210D02*
X522186D01*
Y-350439D01*
X641339Y-327461D02*
Y-323524D01*
X639567Y-327461D02*
X641339D01*
X632677D02*
Y-323524D01*
Y-327461D02*
X634449D01*
X660039Y-327559D02*
Y-323622D01*
X658268Y-327559D02*
X660039D01*
X651378D02*
Y-323622D01*
Y-327559D02*
X653150D01*
X72638Y-216535D02*
X78937D01*
X72638D02*
Y-208661D01*
X78937D01*
Y-216535D02*
Y-208661D01*
X80315Y-217520D02*
X83661D01*
X71653Y-163386D02*
X77953D01*
X71653D02*
Y-155512D01*
X77953D01*
Y-163386D02*
Y-155512D01*
X79331Y-164370D02*
X82677D01*
X37205Y8465D02*
Y15157D01*
X43504Y8465D02*
Y15157D01*
X30315Y8465D02*
Y15157D01*
X36614Y8465D02*
Y15157D01*
X23425Y8465D02*
Y15157D01*
X29724Y8465D02*
Y15157D01*
X44094Y8465D02*
Y15157D01*
X50394Y8465D02*
Y15157D01*
X92913Y-117913D02*
Y-115551D01*
X95276D01*
X111417D02*
X113779D01*
Y-117913D02*
Y-115551D01*
Y-136417D02*
Y-134055D01*
X111417Y-136417D02*
X113779D01*
X92913D02*
Y-134055D01*
Y-136417D02*
X95276D01*
X79823Y-112008D02*
X80020D01*
X79823Y-108465D02*
X80020D01*
X72539Y-128839D02*
Y-121949D01*
X79035Y-128839D02*
Y-121949D01*
X72638Y-268701D02*
X78937D01*
X72638D02*
Y-260827D01*
X78937D01*
Y-268701D02*
Y-260827D01*
X80315Y-269685D02*
X83661D01*
X49409Y-264961D02*
Y-260630D01*
Y-159646D02*
Y-155315D01*
X71653Y-322835D02*
X77953D01*
X71653D02*
Y-314961D01*
X77953D01*
Y-322835D02*
Y-314961D01*
X79331Y-323819D02*
X82677D01*
X49409Y-319094D02*
Y-314764D01*
Y-212795D02*
Y-208465D01*
X534055Y-1063D02*
X594055D01*
Y18937D01*
X534055D02*
X594055D01*
X534055Y-1063D02*
Y18937D01*
X669193Y-26476D02*
X670177D01*
X669193Y-20768D02*
X670177D01*
X612697Y-18651D02*
X613681D01*
X612697Y-24360D02*
X613681D01*
X86713Y-94832D02*
Y-93848D01*
X92421Y-94832D02*
Y-93848D01*
X120177Y-76525D02*
Y-75541D01*
X125886Y-76525D02*
Y-75541D01*
X27756Y-171653D02*
X41142D01*
Y-187795D02*
Y-171653D01*
X27756Y-187795D02*
Y-171653D01*
Y-187795D02*
X41043D01*
X27756Y-279331D02*
X41142D01*
Y-295472D02*
Y-279331D01*
X27756Y-295472D02*
Y-279331D01*
Y-295472D02*
X41043D01*
X285433Y-131289D02*
Y-111604D01*
X292520Y-131289D02*
Y-111604D01*
X285433D02*
X292520D01*
X285433Y-131289D02*
X292520D01*
X214567Y-131742D02*
Y-112057D01*
X222441Y-131742D02*
Y-112057D01*
X214567D02*
X222441D01*
X214567Y-131742D02*
X222441D01*
X510630Y-118750D02*
X520866D01*
X510630Y-130954D02*
X520866D01*
X454921Y-126514D02*
Y-125159D01*
X459414Y-128986D02*
X461846D01*
X466339Y-126514D02*
Y-125159D01*
D16*
X-18799Y-190157D02*
G03*
X-18406Y-190157I197J0D01*
G01*
D02*
G03*
X-18799Y-190157I-197J0D01*
G01*
Y-242913D02*
G03*
X-18406Y-242913I197J0D01*
G01*
D02*
G03*
X-18799Y-242913I-197J0D01*
G01*
Y-296457D02*
G03*
X-18406Y-296457I197J0D01*
G01*
D02*
G03*
X-18799Y-296457I-197J0D01*
G01*
Y-349213D02*
G03*
X-18406Y-349213I197J0D01*
G01*
D02*
G03*
X-18799Y-349213I-197J0D01*
G01*
Y-116339D02*
G03*
X-18406Y-116339I197J0D01*
G01*
D02*
G03*
X-18799Y-116339I-197J0D01*
G01*
Y-73032D02*
G03*
X-18406Y-73032I197J0D01*
G01*
D02*
G03*
X-18799Y-73032I-197J0D01*
G01*
X-16437Y-185433D02*
Y-179134D01*
Y-238189D02*
Y-231890D01*
Y-291732D02*
Y-285433D01*
Y-344488D02*
Y-338189D01*
Y-111614D02*
Y-105315D01*
Y-68307D02*
Y-62008D01*
D17*
X289370Y-114753D02*
G03*
X289370Y-114753I-787J0D01*
G01*
X218504Y-115206D02*
G03*
X218504Y-115206I-787J0D01*
G01*
D18*
X665945Y-322638D02*
X667126D01*
X662795D02*
X663976D01*
X665945Y-323819D02*
Y-321457D01*
X663976Y-323819D02*
Y-321457D01*
Y-323819D02*
X665945Y-322638D01*
X663976Y-321457D02*
X665945Y-322638D01*
X665551Y-314370D02*
X666732D01*
X662402D02*
X663583D01*
X665551Y-315551D02*
Y-313189D01*
X663583Y-315551D02*
Y-313189D01*
Y-315551D02*
X665551Y-314370D01*
X663583Y-313189D02*
X665551Y-314370D01*
X619882Y-305709D02*
X621063D01*
X623032D02*
X624213D01*
X621063Y-306890D02*
Y-304528D01*
X623032Y-306890D02*
Y-304528D01*
X621063Y-305709D02*
X623032Y-304528D01*
X621063Y-305709D02*
X623032Y-306890D01*
X631299Y-243110D02*
X632480D01*
X634449D02*
X635630D01*
X632480Y-244291D02*
Y-241929D01*
X634449Y-244291D02*
Y-241929D01*
X632480Y-243110D02*
X634449Y-241929D01*
X632480Y-243110D02*
X634449Y-244291D01*
X614764Y-153347D02*
X615945D01*
X617913D02*
X619095D01*
X615945Y-154528D02*
Y-152165D01*
X617913Y-154528D02*
Y-152165D01*
X615945Y-153347D02*
X617913Y-152165D01*
X615945Y-153347D02*
X617913Y-154528D01*
X612008Y-126181D02*
Y-125000D01*
Y-123031D02*
Y-121850D01*
X610827Y-125000D02*
X613189D01*
X610827Y-123031D02*
X613189D01*
X610827D02*
X612008Y-125000D01*
X613189Y-123031D01*
X567520Y-153740D02*
X568701D01*
X564370D02*
X565551D01*
X567520Y-154921D02*
Y-152559D01*
X565551Y-154921D02*
Y-152559D01*
Y-154921D02*
X567520Y-153740D01*
X565551Y-152559D02*
X567520Y-153740D01*
X51968Y17717D02*
X53150Y19685D01*
X50787D02*
X51968Y17717D01*
X50787Y19685D02*
X53150D01*
X50787Y17717D02*
X53150D01*
X51968Y19685D02*
Y20866D01*
Y16535D02*
Y17717D01*
X37008D02*
X38189Y19685D01*
X35827D02*
X37008Y17717D01*
X35827Y19685D02*
X38189D01*
X35827Y17717D02*
X38189D01*
X37008Y19685D02*
Y20866D01*
Y16535D02*
Y17717D01*
X30315D02*
X31496Y19685D01*
X29134D02*
X30315Y17717D01*
X29134Y19685D02*
X31496D01*
X29134Y17717D02*
X31496D01*
X30315Y19685D02*
Y20866D01*
Y16535D02*
Y17717D01*
X20079Y16929D02*
X21260Y18898D01*
X18898D02*
X20079Y16929D01*
X18898Y18898D02*
X21260D01*
X18898Y16929D02*
X21260D01*
X20079Y18898D02*
Y20079D01*
Y15748D02*
Y16929D01*
X-7480Y-344882D02*
X-6299Y-342913D01*
X-5118Y-344882D01*
X-7480D02*
X-5118D01*
X-7480Y-342913D02*
X-5118D01*
X-6299Y-346063D02*
Y-344882D01*
Y-342913D02*
Y-341732D01*
X-8268Y-291339D02*
X-7087Y-289370D01*
X-5906Y-291339D01*
X-8268D02*
X-5906D01*
X-8268Y-289370D02*
X-5906D01*
X-7087Y-292520D02*
Y-291339D01*
Y-289370D02*
Y-288189D01*
X-7874Y-237402D02*
X-6693Y-235433D01*
X-5512Y-237402D01*
X-7874D02*
X-5512D01*
X-7874Y-235433D02*
X-5512D01*
X-6693Y-238583D02*
Y-237402D01*
Y-235433D02*
Y-234252D01*
X-18504Y-123622D02*
X-17323Y-121653D01*
X-16142Y-123622D01*
X-18504D02*
X-16142D01*
X-18504Y-121653D02*
X-16142D01*
X-17323Y-124803D02*
Y-123622D01*
Y-121653D02*
Y-120472D01*
X-18504Y-80315D02*
X-17323Y-78347D01*
X-16142Y-80315D01*
X-18504D02*
X-16142D01*
X-18504Y-78347D02*
X-16142D01*
X-17323Y-81496D02*
Y-80315D01*
Y-78347D02*
Y-77165D01*
X-3937Y-181102D02*
Y-179921D01*
Y-184252D02*
Y-183071D01*
X-5118Y-181102D02*
X-2756D01*
X-5118Y-183071D02*
X-2756D01*
X-3937Y-181102D02*
X-2756Y-183071D01*
X-5118D02*
X-3937Y-181102D01*
X571395Y-227439D02*
X574727Y-224107D01*
Y-227439D02*
X571395Y-224107D01*
X573061Y-227439D02*
Y-224107D01*
X574727Y-225773D02*
X571395D01*
X560220Y-286046D02*
X563553Y-282714D01*
Y-286046D02*
X560220Y-282714D01*
X561887Y-286046D02*
Y-282714D01*
X563553Y-284380D02*
X560220D01*
D19*
X542840Y-322840D02*
Y-145674D01*
X326304Y-322840D02*
X542840D01*
X326304Y-145674D02*
X542840D01*
X326304Y-322840D02*
Y-145674D01*
D20*
X571396Y-224890D02*
Y-221001D01*
Y-201990D02*
X574717D01*
X598196Y-205879D02*
Y-201990D01*
X594876Y-224890D02*
X598196D01*
X571396D02*
X574717D01*
X571396Y-205879D02*
Y-201990D01*
X594876D02*
X598196D01*
Y-224890D02*
Y-221001D01*
X560222Y-283497D02*
Y-279608D01*
Y-260597D02*
X563543D01*
X587022Y-264486D02*
Y-260597D01*
X583702Y-283497D02*
X587022D01*
X560222D02*
X563543D01*
X560222Y-264486D02*
Y-260597D01*
X583702D02*
X587022D01*
Y-283497D02*
Y-279608D01*
X536556Y-334738D02*
Y-328738D01*
X536162Y-350880D02*
Y-344880D01*
X652118Y-342520D02*
X658118D01*
X634008Y-342913D02*
X640008D01*
X573759Y-123866D02*
Y-117866D01*
X581359Y-123866D02*
Y-117866D01*
X594882Y-161417D02*
Y-157480D01*
X353680Y-103394D02*
Y-97394D01*
X361280Y-103394D02*
Y-97394D01*
X113425Y-265600D02*
Y-261663D01*
D21*
X658356Y-41584D02*
Y-10088D01*
X622923Y-41584D02*
Y-10088D01*
Y-41584D02*
X658356D01*
X622923Y-10088D02*
X658356D01*
X65069Y-77608D02*
Y-46112D01*
X100502Y-77608D02*
Y-46112D01*
X65069D02*
X100502D01*
X65069Y-77608D02*
X100502D01*
D22*
X386614Y-303085D02*
X388779Y-300724D01*
X473031D02*
X475196Y-303085D01*
X470405Y-300724D02*
X473031D01*
X388779D02*
X391405D01*
X386614Y-314109D02*
Y-303085D01*
Y-314109D02*
X388779D01*
Y-316472D02*
Y-314109D01*
Y-316472D02*
X391405D01*
X475196Y-314109D02*
Y-303085D01*
X473031Y-314109D02*
X475196D01*
X473031Y-316472D02*
Y-314109D01*
X470405Y-316472D02*
X473031D01*
X346416Y-189749D02*
X348778Y-191914D01*
X346416Y-278331D02*
X348778Y-276166D01*
Y-273540D01*
Y-194540D02*
Y-191914D01*
X335392Y-189749D02*
X346416D01*
X335392Y-191914D02*
Y-189749D01*
X333030Y-191914D02*
X335392D01*
X333030Y-194540D02*
Y-191914D01*
X335392Y-278331D02*
X346416D01*
X335392D02*
Y-276166D01*
X333030D02*
X335392D01*
X333030D02*
Y-273540D01*
X473040Y-168351D02*
X475206Y-165989D01*
X386624D02*
X388789Y-168351D01*
X391415D01*
X470414D02*
X473040D01*
X475206Y-165989D02*
Y-154965D01*
X473040D02*
X475206D01*
X473040D02*
Y-152603D01*
X470414D02*
X473040D01*
X386624Y-165989D02*
Y-154965D01*
X388789D01*
Y-152603D01*
X391415D01*
X520521Y-276176D02*
X522883Y-278341D01*
X520521Y-191924D02*
X522883Y-189759D01*
X520521Y-194550D02*
Y-191924D01*
Y-276176D02*
Y-273550D01*
X522883Y-278341D02*
X533907D01*
Y-276176D01*
X536269D01*
Y-273550D01*
X522883Y-189759D02*
X533907D01*
Y-191924D02*
Y-189759D01*
Y-191924D02*
X536269D01*
Y-194550D02*
Y-191924D01*
D23*
X621479Y-34608D02*
Y-35608D01*
X621979Y-36108D01*
X623978D01*
X624478Y-35608D01*
Y-34608D01*
X623978Y-34108D01*
X621979D01*
X621479Y-34608D01*
X622479Y-33109D02*
X624478D01*
X623479D01*
X622979Y-32609D01*
X622479Y-32109D01*
Y-31609D01*
X624478Y-30110D02*
Y-29110D01*
Y-29610D01*
X622479D01*
Y-30110D01*
X625478Y-26611D02*
Y-26111D01*
X624978Y-25611D01*
X622479D01*
Y-27111D01*
X622979Y-27611D01*
X623978D01*
X624478Y-27111D01*
Y-25611D01*
Y-19613D02*
Y-21612D01*
X622479Y-19613D01*
X621979D01*
X621479Y-20113D01*
Y-21113D01*
X621979Y-21612D01*
X622479Y-18613D02*
X624478Y-16614D01*
X623479Y-17614D01*
X622479Y-16614D01*
X624478Y-18613D01*
Y-14115D02*
X621479D01*
X622979Y-15615D01*
Y-13615D01*
X101509Y-73240D02*
Y-74239D01*
X102008Y-74739D01*
X104008D01*
X104508Y-74239D01*
Y-73240D01*
X104008Y-72740D01*
X102008D01*
X101509Y-73240D01*
X102508Y-71740D02*
X104508D01*
X103508D01*
X103008Y-71241D01*
X102508Y-70741D01*
Y-70241D01*
X104508Y-68741D02*
Y-67742D01*
Y-68242D01*
X102508D01*
Y-68741D01*
X105507Y-65242D02*
Y-64743D01*
X105008Y-64243D01*
X102508D01*
Y-65742D01*
X103008Y-66242D01*
X104008D01*
X104508Y-65742D01*
Y-64243D01*
Y-58245D02*
Y-60244D01*
X102508Y-58245D01*
X102008D01*
X101509Y-58745D01*
Y-59744D01*
X102008Y-60244D01*
X102508Y-57245D02*
X104508Y-55246D01*
X103508Y-56245D01*
X102508Y-55246D01*
X104508Y-57245D01*
Y-52746D02*
X101509D01*
X103008Y-54246D01*
Y-52247D01*
X142407Y-114061D02*
X140408D01*
X139408Y-113061D01*
X140408Y-112061D01*
X142407D01*
X140908D01*
Y-114061D01*
X142407Y-111062D02*
X139408D01*
X142407Y-109062D01*
X139408D01*
X142407Y-108063D02*
X140408D01*
X139408Y-107063D01*
X140408Y-106063D01*
X142407D01*
X140908D01*
Y-108063D01*
X139408Y-105063D02*
X142407D01*
Y-103064D01*
X139408Y-100565D02*
Y-101565D01*
X139908Y-102065D01*
X141907D01*
X142407Y-101565D01*
Y-100565D01*
X141907Y-100065D01*
X139908D01*
X139408Y-100565D01*
X139908Y-97066D02*
X139408Y-97566D01*
Y-98566D01*
X139908Y-99066D01*
X141907D01*
X142407Y-98566D01*
Y-97566D01*
X141907Y-97066D01*
X140908D01*
Y-98066D01*
X139408Y-91068D02*
Y-93067D01*
X140908D01*
Y-92068D01*
Y-93067D01*
X142407D01*
Y-90068D02*
X139408D01*
Y-88569D01*
X139908Y-88069D01*
X140908D01*
X141407Y-88569D01*
Y-90068D01*
Y-89069D02*
X142407Y-88069D01*
X139408Y-85070D02*
Y-87069D01*
X142407D01*
Y-85070D01*
X140908Y-87069D02*
Y-86070D01*
X141907Y-82071D02*
X139908D01*
X139408Y-82571D01*
Y-83570D01*
X139908Y-84070D01*
X141907D01*
X142407Y-83570D01*
Y-82571D01*
X141407Y-83071D02*
X142407Y-82071D01*
Y-82571D02*
X141907Y-82071D01*
X326884Y-114454D02*
X328217D01*
X327551D01*
Y-110456D01*
X326884Y-111122D01*
X332882Y-114454D02*
X330217D01*
X332882Y-111788D01*
Y-111122D01*
X332216Y-110456D01*
X330883D01*
X330217Y-111122D01*
X334215Y-110456D02*
Y-113121D01*
X335548Y-114454D01*
X336881Y-113121D01*
Y-110456D01*
X342213Y-114454D02*
Y-110456D01*
X343546Y-111788D01*
X344878Y-110456D01*
Y-114454D01*
X346211D02*
Y-111788D01*
X347544Y-110456D01*
X348877Y-111788D01*
Y-114454D01*
Y-112455D01*
X346211D01*
X352876Y-111122D02*
X352209Y-110456D01*
X350876D01*
X350210Y-111122D01*
Y-113788D01*
X350876Y-114454D01*
X352209D01*
X352876Y-113788D01*
X325703Y-134744D02*
X326370Y-134078D01*
X327702D01*
X328369Y-134744D01*
Y-135411D01*
X327702Y-136077D01*
X327036D01*
X327702D01*
X328369Y-136743D01*
Y-137410D01*
X327702Y-138076D01*
X326370D01*
X325703Y-137410D01*
X329702Y-138076D02*
Y-137410D01*
X330368D01*
Y-138076D01*
X329702D01*
X333034Y-134744D02*
X333701Y-134078D01*
X335033D01*
X335700Y-134744D01*
Y-135411D01*
X335033Y-136077D01*
X334367D01*
X335033D01*
X335700Y-136743D01*
Y-137410D01*
X335033Y-138076D01*
X333701D01*
X333034Y-137410D01*
X337033Y-134078D02*
Y-136743D01*
X338366Y-138076D01*
X339699Y-136743D01*
Y-134078D01*
X345030Y-138076D02*
Y-134078D01*
X346363Y-135411D01*
X347696Y-134078D01*
Y-138076D01*
X349029D02*
Y-135411D01*
X350362Y-134078D01*
X351695Y-135411D01*
Y-138076D01*
Y-136077D01*
X349029D01*
X355694Y-134744D02*
X355027Y-134078D01*
X353694D01*
X353028Y-134744D01*
Y-137410D01*
X353694Y-138076D01*
X355027D01*
X355694Y-137410D01*
X331125Y-122267D02*
X328459D01*
Y-124266D01*
X329792Y-123600D01*
X330458D01*
X331125Y-124266D01*
Y-125599D01*
X330458Y-126265D01*
X329125D01*
X328459Y-125599D01*
X332458Y-122267D02*
Y-124932D01*
X333791Y-126265D01*
X335124Y-124932D01*
Y-122267D01*
X340455Y-126265D02*
Y-122267D01*
X341788Y-123600D01*
X343121Y-122267D01*
Y-126265D01*
X344454D02*
Y-123600D01*
X345787Y-122267D01*
X347120Y-123600D01*
Y-126265D01*
Y-124266D01*
X344454D01*
X351118Y-122933D02*
X350452Y-122267D01*
X349119D01*
X348453Y-122933D01*
Y-125599D01*
X349119Y-126265D01*
X350452D01*
X351118Y-125599D01*
X170617Y-132534D02*
X170117Y-133034D01*
Y-134033D01*
X170617Y-134533D01*
X172616D01*
X173116Y-134033D01*
Y-133034D01*
X172616Y-132534D01*
X171616D01*
Y-133533D01*
X173116Y-131534D02*
X170117D01*
X173116Y-129535D01*
X170117D01*
Y-128535D02*
X173116D01*
Y-127035D01*
X172616Y-126536D01*
X170617D01*
X170117Y-127035D01*
Y-128535D01*
X180747Y-134533D02*
X182746D01*
X183746Y-133533D01*
X182746Y-132534D01*
X180747D01*
X181246Y-129535D02*
X180747Y-130034D01*
Y-131034D01*
X181246Y-131534D01*
X183246D01*
X183746Y-131034D01*
Y-130034D01*
X183246Y-129535D01*
X181246Y-126536D02*
X180747Y-127035D01*
Y-128035D01*
X181246Y-128535D01*
X183246D01*
X183746Y-128035D01*
Y-127035D01*
X183246Y-126536D01*
X160774Y-132140D02*
X160274Y-132640D01*
Y-133640D01*
X160774Y-134139D01*
X161274D01*
X161774Y-133640D01*
Y-132640D01*
X162274Y-132140D01*
X162773D01*
X163273Y-132640D01*
Y-133640D01*
X162773Y-134139D01*
X160774Y-129141D02*
X160274Y-129641D01*
Y-130640D01*
X160774Y-131140D01*
X162773D01*
X163273Y-130640D01*
Y-129641D01*
X162773Y-129141D01*
X160274Y-128141D02*
X163273D01*
Y-126142D01*
X149750Y-132534D02*
X149251Y-133034D01*
Y-134033D01*
X149750Y-134533D01*
X150250D01*
X150750Y-134033D01*
Y-133034D01*
X151250Y-132534D01*
X151750D01*
X152250Y-133034D01*
Y-134033D01*
X151750Y-134533D01*
X149251Y-131534D02*
X152250D01*
Y-130034D01*
X151750Y-129535D01*
X149750D01*
X149251Y-130034D01*
Y-131534D01*
X152250Y-128535D02*
X150250D01*
X149251Y-127535D01*
X150250Y-126536D01*
X152250D01*
X150750D01*
Y-128535D01*
X40892Y-73724D02*
X40392Y-74224D01*
Y-75224D01*
X40892Y-75724D01*
X42891D01*
X43391Y-75224D01*
Y-74224D01*
X42891Y-73724D01*
X41892D01*
Y-74724D01*
X43391Y-72725D02*
X40392D01*
X43391Y-70725D01*
X40392D01*
X40892Y-67726D02*
X40392Y-68226D01*
Y-69226D01*
X40892Y-69726D01*
X41392D01*
X41892Y-69226D01*
Y-68226D01*
X42392Y-67726D01*
X42891D01*
X43391Y-68226D01*
Y-69226D01*
X42891Y-69726D01*
X40892Y-64727D02*
X40392Y-65227D01*
Y-66227D01*
X40892Y-66726D01*
X41392D01*
X41892Y-66227D01*
Y-65227D01*
X42392Y-64727D01*
X42891D01*
X43391Y-65227D01*
Y-66227D01*
X42891Y-66726D01*
X43391Y-63727D02*
Y-62728D01*
Y-63228D01*
X40392D01*
X40892Y-63727D01*
X40892Y-119984D02*
X40392Y-120484D01*
Y-121484D01*
X40892Y-121984D01*
X42891D01*
X43391Y-121484D01*
Y-120484D01*
X42891Y-119984D01*
X41892D01*
Y-120984D01*
X43391Y-118984D02*
X40392D01*
X43391Y-116985D01*
X40392D01*
X40892Y-113986D02*
X40392Y-114486D01*
Y-115486D01*
X40892Y-115985D01*
X41392D01*
X41892Y-115486D01*
Y-114486D01*
X42392Y-113986D01*
X42891D01*
X43391Y-114486D01*
Y-115486D01*
X42891Y-115985D01*
X40892Y-110987D02*
X40392Y-111487D01*
Y-112487D01*
X40892Y-112986D01*
X41392D01*
X41892Y-112487D01*
Y-111487D01*
X42392Y-110987D01*
X42891D01*
X43391Y-111487D01*
Y-112487D01*
X42891Y-112986D01*
X43391Y-107988D02*
Y-109987D01*
X41392Y-107988D01*
X40892D01*
X40392Y-108488D01*
Y-109487D01*
X40892Y-109987D01*
X50120Y-120791D02*
Y-117792D01*
X51619D01*
X52119Y-118292D01*
Y-119291D01*
X51619Y-119791D01*
X50120D01*
X51119D02*
X52119Y-120791D01*
X53119D02*
X54118D01*
X53619D01*
Y-117792D01*
X53119Y-118292D01*
X55618Y-120791D02*
X56618D01*
X56118D01*
Y-117792D01*
X55618Y-118292D01*
X58117D02*
X58617Y-117792D01*
X59617D01*
X60116Y-118292D01*
Y-120291D01*
X59617Y-120791D01*
X58617D01*
X58117Y-120291D01*
Y-118292D01*
X50264Y-111342D02*
Y-108343D01*
X51763D01*
X52263Y-108843D01*
Y-109843D01*
X51763Y-110342D01*
X50264D01*
X51263D02*
X52263Y-111342D01*
X53263D02*
X54262D01*
X53762D01*
Y-108343D01*
X53263Y-108843D01*
X55762D02*
X56262Y-108343D01*
X57261D01*
X57761Y-108843D01*
Y-110842D01*
X57261Y-111342D01*
X56262D01*
X55762Y-110842D01*
Y-108843D01*
X58761Y-110842D02*
X59261Y-111342D01*
X60260D01*
X60760Y-110842D01*
Y-108843D01*
X60260Y-108343D01*
X59261D01*
X58761Y-108843D01*
Y-109343D01*
X59261Y-109843D01*
X60760D01*
X50264Y-116066D02*
Y-113067D01*
X51763D01*
X52263Y-113567D01*
Y-114567D01*
X51763Y-115067D01*
X50264D01*
X51263D02*
X52263Y-116066D01*
X53263D02*
X54262D01*
X53762D01*
Y-113067D01*
X53263Y-113567D01*
X55762D02*
X56262Y-113067D01*
X57261D01*
X57761Y-113567D01*
Y-115567D01*
X57261Y-116066D01*
X56262D01*
X55762Y-115567D01*
Y-113567D01*
X58761D02*
X59261Y-113067D01*
X60260D01*
X60760Y-113567D01*
Y-114067D01*
X60260Y-114567D01*
X60760Y-115067D01*
Y-115567D01*
X60260Y-116066D01*
X59261D01*
X58761Y-115567D01*
Y-115067D01*
X59261Y-114567D01*
X58761Y-114067D01*
Y-113567D01*
X59261Y-114567D02*
X60260D01*
X261886Y-115618D02*
X264885D01*
Y-117117D01*
X264386Y-117617D01*
X263386D01*
X262886Y-117117D01*
Y-115618D01*
Y-116618D02*
X261886Y-117617D01*
Y-118617D02*
Y-119617D01*
Y-119117D01*
X264885D01*
X264386Y-118617D01*
Y-121116D02*
X264885Y-121616D01*
Y-122616D01*
X264386Y-123115D01*
X262386D01*
X261886Y-122616D01*
Y-121616D01*
X262386Y-121116D01*
X264386D01*
X264885Y-124115D02*
Y-126114D01*
X264386D01*
X262386Y-124115D01*
X261886D01*
X254988Y-101499D02*
Y-98501D01*
X256487D01*
X256987Y-99000D01*
Y-100000D01*
X256487Y-100500D01*
X254988D01*
X255988D02*
X256987Y-101499D01*
X257987D02*
X258987D01*
X258487D01*
Y-98501D01*
X257987Y-99000D01*
X260486D02*
X260986Y-98501D01*
X261986D01*
X262486Y-99000D01*
Y-101000D01*
X261986Y-101499D01*
X260986D01*
X260486Y-101000D01*
Y-99000D01*
X265484Y-98501D02*
X264485Y-99000D01*
X263485Y-100000D01*
Y-101000D01*
X263985Y-101499D01*
X264985D01*
X265484Y-101000D01*
Y-100500D01*
X264985Y-100000D01*
X263485D01*
X231760Y-95200D02*
Y-92201D01*
X233259D01*
X233759Y-92701D01*
Y-93701D01*
X233259Y-94201D01*
X231760D01*
X232759D02*
X233759Y-95200D01*
X234759D02*
X235758D01*
X235258D01*
Y-92201D01*
X234759Y-92701D01*
X237258D02*
X237758Y-92201D01*
X238757D01*
X239257Y-92701D01*
Y-94700D01*
X238757Y-95200D01*
X237758D01*
X237258Y-94700D01*
Y-92701D01*
X242256Y-92201D02*
X240257D01*
Y-93701D01*
X241256Y-93201D01*
X241756D01*
X242256Y-93701D01*
Y-94700D01*
X241756Y-95200D01*
X240757D01*
X240257Y-94700D01*
X236145Y-129658D02*
X233146D01*
Y-128158D01*
X233646Y-127658D01*
X234646D01*
X235145Y-128158D01*
Y-129658D01*
Y-128658D02*
X236145Y-127658D01*
Y-126659D02*
Y-125659D01*
Y-126159D01*
X233146D01*
X233646Y-126659D01*
Y-124160D02*
X233146Y-123660D01*
Y-122660D01*
X233646Y-122160D01*
X235645D01*
X236145Y-122660D01*
Y-123660D01*
X235645Y-124160D01*
X233646D01*
X236145Y-119661D02*
X233146D01*
X234646Y-121160D01*
Y-119161D01*
X581595Y-107926D02*
Y-104927D01*
X583095D01*
X583595Y-105427D01*
Y-106427D01*
X583095Y-106927D01*
X581595D01*
X582595D02*
X583595Y-107926D01*
X584594D02*
X585594D01*
X585094D01*
Y-104927D01*
X584594Y-105427D01*
X587093D02*
X587593Y-104927D01*
X588593D01*
X589093Y-105427D01*
Y-107426D01*
X588593Y-107926D01*
X587593D01*
X587093Y-107426D01*
Y-105427D01*
X590093D02*
X590592Y-104927D01*
X591592D01*
X592092Y-105427D01*
Y-105927D01*
X591592Y-106427D01*
X591092D01*
X591592D01*
X592092Y-106927D01*
Y-107426D01*
X591592Y-107926D01*
X590592D01*
X590093Y-107426D01*
X577823Y-78271D02*
Y-75272D01*
X579322D01*
X579822Y-75772D01*
Y-76772D01*
X579322Y-77271D01*
X577823D01*
X578822D02*
X579822Y-78271D01*
X580822D02*
X581821D01*
X581321D01*
Y-75272D01*
X580822Y-75772D01*
X583321D02*
X583821Y-75272D01*
X584820D01*
X585320Y-75772D01*
Y-77771D01*
X584820Y-78271D01*
X583821D01*
X583321Y-77771D01*
Y-75772D01*
X588319Y-78271D02*
X586320D01*
X588319Y-76272D01*
Y-75772D01*
X587819Y-75272D01*
X586820D01*
X586320Y-75772D01*
X600763Y-99531D02*
Y-96532D01*
X602263D01*
X602763Y-97032D01*
Y-98032D01*
X602263Y-98531D01*
X600763D01*
X601763D02*
X602763Y-99531D01*
X603762D02*
X604762D01*
X604262D01*
Y-96532D01*
X603762Y-97032D01*
X606262D02*
X606761Y-96532D01*
X607761D01*
X608261Y-97032D01*
Y-99031D01*
X607761Y-99531D01*
X606761D01*
X606262Y-99031D01*
Y-97032D01*
X609261Y-99531D02*
X610260D01*
X609760D01*
Y-96532D01*
X609261Y-97032D01*
X603807Y-79059D02*
Y-76060D01*
X605306D01*
X605806Y-76559D01*
Y-77559D01*
X605306Y-78059D01*
X603807D01*
X604807D02*
X605806Y-79059D01*
X606806D02*
X607805D01*
X607306D01*
Y-76060D01*
X606806Y-76559D01*
X609305D02*
X609805Y-76060D01*
X610805D01*
X611304Y-76559D01*
Y-78559D01*
X610805Y-79059D01*
X609805D01*
X609305Y-78559D01*
Y-76559D01*
X612304D02*
X612804Y-76060D01*
X613804D01*
X614303Y-76559D01*
Y-78559D01*
X613804Y-79059D01*
X612804D01*
X612304Y-78559D01*
Y-76559D01*
X242064Y-131965D02*
Y-134464D01*
X242564Y-134964D01*
X243564D01*
X244064Y-134464D01*
Y-131965D01*
X247063Y-134964D02*
X245063D01*
X247063Y-132965D01*
Y-132465D01*
X246563Y-131965D01*
X245563D01*
X245063Y-132465D01*
X248062D02*
X248562Y-131965D01*
X249562D01*
X250062Y-132465D01*
Y-132965D01*
X249562Y-133465D01*
X249062D01*
X249562D01*
X250062Y-133964D01*
Y-134464D01*
X249562Y-134964D01*
X248562D01*
X248062Y-134464D01*
X579860Y-82752D02*
Y-85252D01*
X580359Y-85751D01*
X581359D01*
X581859Y-85252D01*
Y-82752D01*
X584858Y-85751D02*
X582859D01*
X584858Y-83752D01*
Y-83252D01*
X584358Y-82752D01*
X583358D01*
X582859Y-83252D01*
X587857Y-85751D02*
X585858D01*
X587857Y-83752D01*
Y-83252D01*
X587357Y-82752D01*
X586357D01*
X585858Y-83252D01*
X613037Y-83146D02*
Y-85645D01*
X613536Y-86145D01*
X614536D01*
X615036Y-85645D01*
Y-83146D01*
X618035Y-86145D02*
X616036D01*
X618035Y-84146D01*
Y-83646D01*
X617535Y-83146D01*
X616535D01*
X616036Y-83646D01*
X619035Y-86145D02*
X620034D01*
X619534D01*
Y-83146D01*
X619035Y-83646D01*
X697169Y-52301D02*
X694670D01*
X694170Y-52800D01*
Y-53800D01*
X694670Y-54300D01*
X697169D01*
X694170Y-57299D02*
Y-55300D01*
X696169Y-57299D01*
X696669D01*
X697169Y-56799D01*
Y-55799D01*
X696669Y-55300D01*
Y-58299D02*
X697169Y-58798D01*
Y-59798D01*
X696669Y-60298D01*
X694670D01*
X694170Y-59798D01*
Y-58798D01*
X694670Y-58299D01*
X696669D01*
X430390Y-139945D02*
X429890Y-139445D01*
X428891D01*
X428391Y-139945D01*
Y-140445D01*
X428891Y-140945D01*
X429890D01*
X430390Y-141445D01*
Y-141945D01*
X429890Y-142444D01*
X428891D01*
X428391Y-141945D01*
X431390Y-139445D02*
Y-142444D01*
X432390Y-141445D01*
X433389Y-142444D01*
Y-139445D01*
X434389Y-142444D02*
X435389D01*
X434889D01*
Y-139445D01*
X434389Y-139945D01*
X251513Y-135358D02*
Y-132359D01*
X253013D01*
X253513Y-132859D01*
Y-133858D01*
X253013Y-134358D01*
X251513D01*
X252513D02*
X253513Y-135358D01*
X254512Y-134858D02*
X255012Y-135358D01*
X256012D01*
X256511Y-134858D01*
Y-132859D01*
X256012Y-132359D01*
X255012D01*
X254512Y-132859D01*
Y-133358D01*
X255012Y-133858D01*
X256511D01*
X257511Y-134858D02*
X258011Y-135358D01*
X259011D01*
X259510Y-134858D01*
Y-132859D01*
X259011Y-132359D01*
X258011D01*
X257511Y-132859D01*
Y-133358D01*
X258011Y-133858D01*
X259510D01*
X254663Y-105437D02*
Y-102437D01*
X256162D01*
X256662Y-102937D01*
Y-103937D01*
X256162Y-104437D01*
X254663D01*
X255662D02*
X256662Y-105437D01*
X257662Y-104937D02*
X258162Y-105437D01*
X259161D01*
X259661Y-104937D01*
Y-102937D01*
X259161Y-102437D01*
X258162D01*
X257662Y-102937D01*
Y-103437D01*
X258162Y-103937D01*
X259661D01*
X260661Y-102937D02*
X261161Y-102437D01*
X262160D01*
X262660Y-102937D01*
Y-103437D01*
X262160Y-103937D01*
X262660Y-104437D01*
Y-104937D01*
X262160Y-105437D01*
X261161D01*
X260661Y-104937D01*
Y-104437D01*
X261161Y-103937D01*
X260661Y-103437D01*
Y-102937D01*
X261161Y-103937D02*
X262160D01*
X232222Y-134570D02*
Y-131571D01*
X233721D01*
X234221Y-132071D01*
Y-133071D01*
X233721Y-133571D01*
X232222D01*
X233222D02*
X234221Y-134570D01*
X235221Y-134071D02*
X235721Y-134570D01*
X236720D01*
X237220Y-134071D01*
Y-132071D01*
X236720Y-131571D01*
X235721D01*
X235221Y-132071D01*
Y-132571D01*
X235721Y-133071D01*
X237220D01*
X238220Y-131571D02*
X240219D01*
Y-132071D01*
X238220Y-134071D01*
Y-134570D01*
X239308Y-104649D02*
Y-101650D01*
X240808D01*
X241308Y-102150D01*
Y-103150D01*
X240808Y-103649D01*
X239308D01*
X240308D02*
X241308Y-104649D01*
X242307Y-104149D02*
X242807Y-104649D01*
X243807D01*
X244307Y-104149D01*
Y-102150D01*
X243807Y-101650D01*
X242807D01*
X242307Y-102150D01*
Y-102650D01*
X242807Y-103150D01*
X244307D01*
X247306Y-101650D02*
X246306Y-102150D01*
X245306Y-103150D01*
Y-104149D01*
X245806Y-104649D01*
X246806D01*
X247306Y-104149D01*
Y-103649D01*
X246806Y-103150D01*
X245306D01*
X404255Y-122896D02*
X401256D01*
Y-121397D01*
X401756Y-120897D01*
X402756D01*
X403256Y-121397D01*
Y-122896D01*
Y-121897D02*
X404255Y-120897D01*
X403756Y-119897D02*
X404255Y-119397D01*
Y-118398D01*
X403756Y-117898D01*
X401756D01*
X401256Y-118398D01*
Y-119397D01*
X401756Y-119897D01*
X402256D01*
X402756Y-119397D01*
Y-117898D01*
X401256Y-114899D02*
Y-116898D01*
X402756D01*
X402256Y-115899D01*
Y-115399D01*
X402756Y-114899D01*
X403756D01*
X404255Y-115399D01*
Y-116398D01*
X403756Y-116898D01*
X441414Y-115293D02*
X444413D01*
Y-116792D01*
X443913Y-117292D01*
X442913D01*
X442414Y-116792D01*
Y-115293D01*
Y-116292D02*
X441414Y-117292D01*
X441914Y-118292D02*
X441414Y-118791D01*
Y-119791D01*
X441914Y-120291D01*
X443913D01*
X444413Y-119791D01*
Y-118791D01*
X443913Y-118292D01*
X443413D01*
X442913Y-118791D01*
Y-120291D01*
X441414Y-122790D02*
X444413D01*
X442913Y-121291D01*
Y-123290D01*
X560962Y-101106D02*
Y-98107D01*
X562461D01*
X562961Y-98607D01*
Y-99606D01*
X562461Y-100106D01*
X560962D01*
X561962D02*
X562961Y-101106D01*
X563961Y-100606D02*
X564461Y-101106D01*
X565460D01*
X565960Y-100606D01*
Y-98607D01*
X565460Y-98107D01*
X564461D01*
X563961Y-98607D01*
Y-99107D01*
X564461Y-99606D01*
X565960D01*
X566960Y-98607D02*
X567460Y-98107D01*
X568460D01*
X568959Y-98607D01*
Y-99107D01*
X568460Y-99606D01*
X567960D01*
X568460D01*
X568959Y-100106D01*
Y-100606D01*
X568460Y-101106D01*
X567460D01*
X566960Y-100606D01*
X592064Y-103862D02*
Y-100863D01*
X593564D01*
X594064Y-101363D01*
Y-102362D01*
X593564Y-102862D01*
X592064D01*
X593064D02*
X594064Y-103862D01*
X595063Y-103362D02*
X595563Y-103862D01*
X596563D01*
X597063Y-103362D01*
Y-101363D01*
X596563Y-100863D01*
X595563D01*
X595063Y-101363D01*
Y-101862D01*
X595563Y-102362D01*
X597063D01*
X600062Y-103862D02*
X598062D01*
X600062Y-101862D01*
Y-101363D01*
X599562Y-100863D01*
X598562D01*
X598062Y-101363D01*
X568155Y-84964D02*
Y-81965D01*
X569654D01*
X570154Y-82465D01*
Y-83465D01*
X569654Y-83964D01*
X568155D01*
X569154D02*
X570154Y-84964D01*
X571154Y-84464D02*
X571654Y-84964D01*
X572653D01*
X573153Y-84464D01*
Y-82465D01*
X572653Y-81965D01*
X571654D01*
X571154Y-82465D01*
Y-82965D01*
X571654Y-83465D01*
X573153D01*
X574153Y-84964D02*
X575152D01*
X574653D01*
Y-81965D01*
X574153Y-82465D01*
X591414Y-71198D02*
X594413D01*
Y-72698D01*
X593913Y-73198D01*
X592913D01*
X592414Y-72698D01*
Y-71198D01*
Y-72198D02*
X591414Y-73198D01*
X591914Y-74197D02*
X591414Y-74697D01*
Y-75697D01*
X591914Y-76196D01*
X593913D01*
X594413Y-75697D01*
Y-74697D01*
X593913Y-74197D01*
X593413D01*
X592913Y-74697D01*
Y-76196D01*
X593913Y-77196D02*
X594413Y-77696D01*
Y-78696D01*
X593913Y-79196D01*
X591914D01*
X591414Y-78696D01*
Y-77696D01*
X591914Y-77196D01*
X593913D01*
X434584Y-103468D02*
Y-100469D01*
X436084D01*
X436583Y-100969D01*
Y-101969D01*
X436084Y-102468D01*
X434584D01*
X435584D02*
X436583Y-103468D01*
X437583Y-100969D02*
X438083Y-100469D01*
X439082D01*
X439582Y-100969D01*
Y-101469D01*
X439082Y-101969D01*
X439582Y-102468D01*
Y-102968D01*
X439082Y-103468D01*
X438083D01*
X437583Y-102968D01*
Y-102468D01*
X438083Y-101969D01*
X437583Y-101469D01*
Y-100969D01*
X438083Y-101969D02*
X439082D01*
X440582Y-102968D02*
X441082Y-103468D01*
X442082D01*
X442581Y-102968D01*
Y-100969D01*
X442082Y-100469D01*
X441082D01*
X440582Y-100969D01*
Y-101469D01*
X441082Y-101969D01*
X442581D01*
X396395Y-112129D02*
Y-109130D01*
X397895D01*
X398394Y-109630D01*
Y-110630D01*
X397895Y-111130D01*
X396395D01*
X397395D02*
X398394Y-112129D01*
X399394Y-109630D02*
X399894Y-109130D01*
X400894D01*
X401393Y-109630D01*
Y-110130D01*
X400894Y-110630D01*
X401393Y-111130D01*
Y-111630D01*
X400894Y-112129D01*
X399894D01*
X399394Y-111630D01*
Y-111130D01*
X399894Y-110630D01*
X399394Y-110130D01*
Y-109630D01*
X399894Y-110630D02*
X400894D01*
X402393Y-109630D02*
X402893Y-109130D01*
X403893D01*
X404392Y-109630D01*
Y-110130D01*
X403893Y-110630D01*
X404392Y-111130D01*
Y-111630D01*
X403893Y-112129D01*
X402893D01*
X402393Y-111630D01*
Y-111130D01*
X402893Y-110630D01*
X402393Y-110130D01*
Y-109630D01*
X402893Y-110630D02*
X403893D01*
X601907Y-94019D02*
Y-91020D01*
X603406D01*
X603906Y-91520D01*
Y-92520D01*
X603406Y-93019D01*
X601907D01*
X602907D02*
X603906Y-94019D01*
X604906Y-91520D02*
X605406Y-91020D01*
X606405D01*
X606905Y-91520D01*
Y-92020D01*
X606405Y-92520D01*
X606905Y-93019D01*
Y-93519D01*
X606405Y-94019D01*
X605406D01*
X604906Y-93519D01*
Y-93019D01*
X605406Y-92520D01*
X604906Y-92020D01*
Y-91520D01*
X605406Y-92520D02*
X606405D01*
X607905Y-91020D02*
X609904D01*
Y-91520D01*
X607905Y-93519D01*
Y-94019D01*
X632616Y-102287D02*
Y-99288D01*
X634115D01*
X634615Y-99788D01*
Y-100787D01*
X634115Y-101287D01*
X632616D01*
X633615D02*
X634615Y-102287D01*
X635614Y-99788D02*
X636114Y-99288D01*
X637114D01*
X637614Y-99788D01*
Y-100288D01*
X637114Y-100787D01*
X637614Y-101287D01*
Y-101787D01*
X637114Y-102287D01*
X636114D01*
X635614Y-101787D01*
Y-101287D01*
X636114Y-100787D01*
X635614Y-100288D01*
Y-99788D01*
X636114Y-100787D02*
X637114D01*
X640613Y-99288D02*
X639613Y-99788D01*
X638614Y-100787D01*
Y-101787D01*
X639113Y-102287D01*
X640113D01*
X640613Y-101787D01*
Y-101287D01*
X640113Y-100787D01*
X638614D01*
X601907Y-87326D02*
Y-84327D01*
X603406D01*
X603906Y-84827D01*
Y-85827D01*
X603406Y-86327D01*
X601907D01*
X602907D02*
X603906Y-87326D01*
X604906Y-84827D02*
X605406Y-84327D01*
X606405D01*
X606905Y-84827D01*
Y-85327D01*
X606405Y-85827D01*
X606905Y-86327D01*
Y-86826D01*
X606405Y-87326D01*
X605406D01*
X604906Y-86826D01*
Y-86327D01*
X605406Y-85827D01*
X604906Y-85327D01*
Y-84827D01*
X605406Y-85827D02*
X606405D01*
X609904Y-84327D02*
X607905D01*
Y-85827D01*
X608905Y-85327D01*
X609404D01*
X609904Y-85827D01*
Y-86826D01*
X609404Y-87326D01*
X608405D01*
X607905Y-86826D01*
X623560Y-82602D02*
Y-79603D01*
X625060D01*
X625560Y-80103D01*
Y-81102D01*
X625060Y-81602D01*
X623560D01*
X624560D02*
X625560Y-82602D01*
X626559Y-80103D02*
X627059Y-79603D01*
X628059D01*
X628559Y-80103D01*
Y-80603D01*
X628059Y-81102D01*
X628559Y-81602D01*
Y-82102D01*
X628059Y-82602D01*
X627059D01*
X626559Y-82102D01*
Y-81602D01*
X627059Y-81102D01*
X626559Y-80603D01*
Y-80103D01*
X627059Y-81102D02*
X628059D01*
X631058Y-82602D02*
Y-79603D01*
X629558Y-81102D01*
X631558D01*
X685508Y-14505D02*
X688507D01*
Y-16005D01*
X688007Y-16505D01*
X687008D01*
X686508Y-16005D01*
Y-14505D01*
Y-15505D02*
X685508Y-16505D01*
X688007Y-17504D02*
X688507Y-18004D01*
Y-19004D01*
X688007Y-19504D01*
X687508D01*
X687008Y-19004D01*
X686508Y-19504D01*
X686008D01*
X685508Y-19004D01*
Y-18004D01*
X686008Y-17504D01*
X686508D01*
X687008Y-18004D01*
X687508Y-17504D01*
X688007D01*
X687008Y-18004D02*
Y-19004D01*
X688007Y-20503D02*
X688507Y-21003D01*
Y-22003D01*
X688007Y-22503D01*
X687508D01*
X687008Y-22003D01*
Y-21503D01*
Y-22003D01*
X686508Y-22503D01*
X686008D01*
X685508Y-22003D01*
Y-21003D01*
X686008Y-20503D01*
X666474Y-68429D02*
Y-65430D01*
X667973D01*
X668473Y-65930D01*
Y-66929D01*
X667973Y-67429D01*
X666474D01*
X667473D02*
X668473Y-68429D01*
X669473Y-65930D02*
X669973Y-65430D01*
X670972D01*
X671472Y-65930D01*
Y-66429D01*
X670972Y-66929D01*
X671472Y-67429D01*
Y-67929D01*
X670972Y-68429D01*
X669973D01*
X669473Y-67929D01*
Y-67429D01*
X669973Y-66929D01*
X669473Y-66429D01*
Y-65930D01*
X669973Y-66929D02*
X670972D01*
X674471Y-68429D02*
X672472D01*
X674471Y-66429D01*
Y-65930D01*
X673971Y-65430D01*
X672972D01*
X672472Y-65930D01*
X652044Y-75635D02*
X655043D01*
Y-77135D01*
X654543Y-77634D01*
X653543D01*
X653044Y-77135D01*
Y-75635D01*
Y-76635D02*
X652044Y-77634D01*
X654543Y-78634D02*
X655043Y-79134D01*
Y-80134D01*
X654543Y-80633D01*
X654043D01*
X653543Y-80134D01*
X653044Y-80633D01*
X652544D01*
X652044Y-80134D01*
Y-79134D01*
X652544Y-78634D01*
X653044D01*
X653543Y-79134D01*
X654043Y-78634D01*
X654543D01*
X653543Y-79134D02*
Y-80134D01*
X652044Y-81633D02*
Y-82633D01*
Y-82133D01*
X655043D01*
X654543Y-81633D01*
X692551Y-113311D02*
X693550D01*
X693050D01*
Y-110811D01*
X693550Y-110311D01*
X694050D01*
X694550Y-110811D01*
X690051Y-110311D02*
Y-113311D01*
X691551Y-111811D01*
X689551D01*
X688552Y-112811D02*
X688052Y-113311D01*
X687052D01*
X686552Y-112811D01*
Y-112311D01*
X687052Y-111811D01*
X687552D01*
X687052D01*
X686552Y-111311D01*
Y-110811D01*
X687052Y-110311D01*
X688052D01*
X688552Y-110811D01*
X680633Y-109918D02*
Y-107919D01*
X679134D01*
Y-108918D01*
Y-107919D01*
X677634D01*
X680633Y-110917D02*
X677634D01*
Y-112417D01*
X678134Y-112917D01*
X678634D01*
X679134Y-112417D01*
Y-110917D01*
Y-112417D01*
X679634Y-112917D01*
X680133D01*
X680633Y-112417D01*
Y-110917D01*
X677634Y-113917D02*
Y-114916D01*
Y-114416D01*
X680633D01*
X680133Y-113917D01*
X401650Y-134314D02*
X404649D01*
Y-132814D01*
X404149Y-132314D01*
X402150D01*
X401650Y-132814D01*
Y-134314D01*
X404649Y-129315D02*
Y-131315D01*
X402650Y-129315D01*
X402150D01*
X401650Y-129815D01*
Y-130815D01*
X402150Y-131315D01*
X401650Y-126316D02*
Y-128316D01*
X403150D01*
X402650Y-127316D01*
Y-126816D01*
X403150Y-126316D01*
X404149D01*
X404649Y-126816D01*
Y-127816D01*
X404149Y-128316D01*
X444413Y-126316D02*
X441414D01*
Y-127816D01*
X441914Y-128316D01*
X443913D01*
X444413Y-127816D01*
Y-126316D01*
X441414Y-131315D02*
Y-129315D01*
X443413Y-131315D01*
X443913D01*
X444413Y-130815D01*
Y-129815D01*
X443913Y-129315D01*
X441414Y-133814D02*
X444413D01*
X442913Y-132314D01*
Y-134314D01*
X249394Y-101212D02*
X248894Y-101712D01*
Y-102711D01*
X249394Y-103211D01*
X251393D01*
X251893Y-102711D01*
Y-101712D01*
X251393Y-101212D01*
Y-100212D02*
X251893Y-99712D01*
Y-98713D01*
X251393Y-98213D01*
X249394D01*
X248894Y-98713D01*
Y-99712D01*
X249394Y-100212D01*
X249894D01*
X250394Y-99712D01*
Y-98213D01*
X248894Y-95214D02*
X249394Y-96214D01*
X250394Y-97213D01*
X251393D01*
X251893Y-96713D01*
Y-95714D01*
X251393Y-95214D01*
X250893D01*
X250394Y-95714D01*
Y-97213D01*
X596638Y-74047D02*
X596138Y-74546D01*
Y-75546D01*
X596638Y-76046D01*
X598637D01*
X599137Y-75546D01*
Y-74546D01*
X598637Y-74047D01*
Y-73047D02*
X599137Y-72547D01*
Y-71547D01*
X598637Y-71048D01*
X596638D01*
X596138Y-71547D01*
Y-72547D01*
X596638Y-73047D01*
X597138D01*
X597638Y-72547D01*
Y-71048D01*
X596138Y-68049D02*
Y-70048D01*
X597638D01*
X597138Y-69048D01*
Y-68548D01*
X597638Y-68049D01*
X598637D01*
X599137Y-68548D01*
Y-69548D01*
X598637Y-70048D01*
X633827Y-92701D02*
X633328Y-92201D01*
X632328D01*
X631828Y-92701D01*
Y-94700D01*
X632328Y-95200D01*
X633328D01*
X633827Y-94700D01*
X634827D02*
X635327Y-95200D01*
X636327D01*
X636827Y-94700D01*
Y-92701D01*
X636327Y-92201D01*
X635327D01*
X634827Y-92701D01*
Y-93201D01*
X635327Y-93701D01*
X636827D01*
X639326Y-95200D02*
Y-92201D01*
X637826Y-93701D01*
X639825D01*
X691945Y-26347D02*
X692444Y-25847D01*
Y-24848D01*
X691945Y-24348D01*
X689945D01*
X689445Y-24848D01*
Y-25847D01*
X689945Y-26347D01*
Y-27347D02*
X689445Y-27847D01*
Y-28846D01*
X689945Y-29346D01*
X691945D01*
X692444Y-28846D01*
Y-27847D01*
X691945Y-27347D01*
X691445D01*
X690945Y-27847D01*
Y-29346D01*
X691945Y-30346D02*
X692444Y-30846D01*
Y-31845D01*
X691945Y-32345D01*
X691445D01*
X690945Y-31845D01*
Y-31345D01*
Y-31845D01*
X690445Y-32345D01*
X689945D01*
X689445Y-31845D01*
Y-30846D01*
X689945Y-30346D01*
X696669Y-26347D02*
X697169Y-25847D01*
Y-24848D01*
X696669Y-24348D01*
X694670D01*
X694170Y-24848D01*
Y-25847D01*
X694670Y-26347D01*
Y-27347D02*
X694170Y-27847D01*
Y-28846D01*
X694670Y-29346D01*
X696669D01*
X697169Y-28846D01*
Y-27847D01*
X696669Y-27347D01*
X696169D01*
X695669Y-27847D01*
Y-29346D01*
X694170Y-32345D02*
Y-30346D01*
X696169Y-32345D01*
X696669D01*
X697169Y-31845D01*
Y-30846D01*
X696669Y-30346D01*
X671441Y-32602D02*
X670941Y-33102D01*
Y-34101D01*
X671441Y-34601D01*
X673441D01*
X673940Y-34101D01*
Y-33102D01*
X673441Y-32602D01*
Y-31602D02*
X673940Y-31102D01*
Y-30103D01*
X673441Y-29603D01*
X671441D01*
X670941Y-30103D01*
Y-31102D01*
X671441Y-31602D01*
X671941D01*
X672441Y-31102D01*
Y-29603D01*
X673940Y-28603D02*
Y-27604D01*
Y-28103D01*
X670941D01*
X671441Y-28603D01*
X653906Y-109630D02*
X653406Y-109130D01*
X652407D01*
X651907Y-109630D01*
Y-111630D01*
X652407Y-112129D01*
X653406D01*
X653906Y-111630D01*
X654906D02*
X655406Y-112129D01*
X656405D01*
X656905Y-111630D01*
Y-109630D01*
X656405Y-109130D01*
X655406D01*
X654906Y-109630D01*
Y-110130D01*
X655406Y-110630D01*
X656905D01*
X657905Y-109630D02*
X658405Y-109130D01*
X659404D01*
X659904Y-109630D01*
Y-111630D01*
X659404Y-112129D01*
X658405D01*
X657905Y-111630D01*
Y-109630D01*
X683434Y-65929D02*
X682934Y-65430D01*
X681934D01*
X681434Y-65929D01*
Y-67929D01*
X681934Y-68429D01*
X682934D01*
X683434Y-67929D01*
X684433Y-65929D02*
X684933Y-65430D01*
X685933D01*
X686433Y-65929D01*
Y-66429D01*
X685933Y-66929D01*
X686433Y-67429D01*
Y-67929D01*
X685933Y-68429D01*
X684933D01*
X684433Y-67929D01*
Y-67429D01*
X684933Y-66929D01*
X684433Y-66429D01*
Y-65929D01*
X684933Y-66929D02*
X685933D01*
X687432Y-67929D02*
X687932Y-68429D01*
X688932D01*
X689432Y-67929D01*
Y-65929D01*
X688932Y-65430D01*
X687932D01*
X687432Y-65929D01*
Y-66429D01*
X687932Y-66929D01*
X689432D01*
X644700Y-77528D02*
X645200Y-77028D01*
Y-76029D01*
X644700Y-75529D01*
X642701D01*
X642201Y-76029D01*
Y-77028D01*
X642701Y-77528D01*
X644700Y-78528D02*
X645200Y-79028D01*
Y-80027D01*
X644700Y-80527D01*
X644201D01*
X643701Y-80027D01*
X643201Y-80527D01*
X642701D01*
X642201Y-80027D01*
Y-79028D01*
X642701Y-78528D01*
X643201D01*
X643701Y-79028D01*
X644201Y-78528D01*
X644700D01*
X643701Y-79028D02*
Y-80027D01*
X644700Y-81527D02*
X645200Y-82027D01*
Y-83026D01*
X644700Y-83526D01*
X644201D01*
X643701Y-83026D01*
X643201Y-83526D01*
X642701D01*
X642201Y-83026D01*
Y-82027D01*
X642701Y-81527D01*
X643201D01*
X643701Y-82027D01*
X644201Y-81527D01*
X644700D01*
X643701Y-82027D02*
Y-83026D01*
X659267Y-77528D02*
X659767Y-77028D01*
Y-76029D01*
X659267Y-75529D01*
X657268D01*
X656768Y-76029D01*
Y-77028D01*
X657268Y-77528D01*
X659267Y-78528D02*
X659767Y-79028D01*
Y-80027D01*
X659267Y-80527D01*
X658768D01*
X658268Y-80027D01*
X657768Y-80527D01*
X657268D01*
X656768Y-80027D01*
Y-79028D01*
X657268Y-78528D01*
X657768D01*
X658268Y-79028D01*
X658768Y-78528D01*
X659267D01*
X658268Y-79028D02*
Y-80027D01*
X659767Y-81527D02*
Y-83526D01*
X659267D01*
X657268Y-81527D01*
X656768D01*
X667686Y-87189D02*
X667186Y-86690D01*
X666186D01*
X665686Y-87189D01*
Y-89189D01*
X666186Y-89688D01*
X667186D01*
X667686Y-89189D01*
X668685Y-87189D02*
X669185Y-86690D01*
X670185D01*
X670685Y-87189D01*
Y-87689D01*
X670185Y-88189D01*
X670685Y-88689D01*
Y-89189D01*
X670185Y-89688D01*
X669185D01*
X668685Y-89189D01*
Y-88689D01*
X669185Y-88189D01*
X668685Y-87689D01*
Y-87189D01*
X669185Y-88189D02*
X670185D01*
X673684Y-86690D02*
X672684Y-87189D01*
X671684Y-88189D01*
Y-89189D01*
X672184Y-89688D01*
X673184D01*
X673684Y-89189D01*
Y-88689D01*
X673184Y-88189D01*
X671684D01*
X538912Y-177343D02*
X541911D01*
Y-175843D01*
X541411Y-175343D01*
X539412D01*
X538912Y-175843D01*
Y-177343D01*
X541911Y-172344D02*
Y-174344D01*
X539912Y-172344D01*
X539412D01*
X538912Y-172844D01*
Y-173844D01*
X539412Y-174344D01*
Y-171345D02*
X538912Y-170845D01*
Y-169845D01*
X539412Y-169345D01*
X539912D01*
X540412Y-169845D01*
Y-170345D01*
Y-169845D01*
X540911Y-169345D01*
X541411D01*
X541911Y-169845D01*
Y-170845D01*
X541411Y-171345D01*
X691277Y-317248D02*
Y-314248D01*
X692776D01*
X693276Y-314748D01*
Y-315748D01*
X692776Y-316248D01*
X691277D01*
X692277D02*
X693276Y-317248D01*
X694276Y-314248D02*
X696275D01*
Y-314748D01*
X694276Y-316748D01*
Y-317248D01*
X697275Y-314248D02*
X699274D01*
Y-314748D01*
X697275Y-316748D01*
Y-317248D01*
X668836Y-309130D02*
Y-312129D01*
X670335D01*
X670835Y-311630D01*
Y-309630D01*
X670335Y-309130D01*
X668836D01*
X673834Y-312129D02*
X671835D01*
X673834Y-310130D01*
Y-309630D01*
X673335Y-309130D01*
X672335D01*
X671835Y-309630D01*
X674834D02*
X675334Y-309130D01*
X676334D01*
X676833Y-309630D01*
Y-311630D01*
X676334Y-312129D01*
X675334D01*
X674834Y-311630D01*
Y-309630D01*
X623684Y-303468D02*
Y-300469D01*
X622184D01*
X621684Y-300969D01*
Y-302968D01*
X622184Y-303468D01*
X623684D01*
X618685Y-300469D02*
X620685D01*
X618685Y-302468D01*
Y-302968D01*
X619185Y-303468D01*
X620185D01*
X620685Y-302968D01*
X615686Y-300469D02*
X617686D01*
X615686Y-302468D01*
Y-302968D01*
X616186Y-303468D01*
X617186D01*
X617686Y-302968D01*
X629572Y-237871D02*
Y-240870D01*
X631072D01*
X631571Y-240370D01*
Y-238370D01*
X631072Y-237871D01*
X629572D01*
X634570Y-240870D02*
X632571D01*
X634570Y-238870D01*
Y-238370D01*
X634071Y-237871D01*
X633071D01*
X632571Y-238370D01*
X635570Y-240870D02*
X636570D01*
X636070D01*
Y-237871D01*
X635570Y-238370D01*
X657668Y-285115D02*
Y-287614D01*
X658168Y-288114D01*
X659168D01*
X659668Y-287614D01*
Y-285115D01*
X660668Y-288114D02*
X661667D01*
X661167D01*
Y-285115D01*
X660668Y-285614D01*
X663167Y-287614D02*
X663667Y-288114D01*
X664666D01*
X665166Y-287614D01*
Y-285614D01*
X664666Y-285115D01*
X663667D01*
X663167Y-285614D01*
Y-286114D01*
X663667Y-286614D01*
X665166D01*
X573417Y-255981D02*
Y-258480D01*
X573916Y-258980D01*
X574916D01*
X575416Y-258480D01*
Y-255981D01*
X576416Y-258980D02*
X577415D01*
X576915D01*
Y-255981D01*
X576416Y-256481D01*
X578915D02*
X579415Y-255981D01*
X580414D01*
X580914Y-256481D01*
Y-256980D01*
X580414Y-257480D01*
X580914Y-257980D01*
Y-258480D01*
X580414Y-258980D01*
X579415D01*
X578915Y-258480D01*
Y-257980D01*
X579415Y-257480D01*
X578915Y-256980D01*
Y-256481D01*
X579415Y-257480D02*
X580414D01*
X685245Y-242838D02*
Y-240339D01*
X684745Y-239839D01*
X683745D01*
X683246Y-240339D01*
Y-242838D01*
X682246Y-239839D02*
X681246D01*
X681746D01*
Y-242838D01*
X682246Y-242338D01*
X679747Y-242838D02*
X677747D01*
Y-242338D01*
X679747Y-240339D01*
Y-239839D01*
X686946Y-307405D02*
Y-304406D01*
X688446D01*
X688945Y-304906D01*
Y-305906D01*
X688446Y-306405D01*
X686946D01*
X687946D02*
X688945Y-307405D01*
X689945Y-304906D02*
X690445Y-304406D01*
X691445D01*
X691945Y-304906D01*
Y-305406D01*
X691445Y-305906D01*
X691945Y-306405D01*
Y-306905D01*
X691445Y-307405D01*
X690445D01*
X689945Y-306905D01*
Y-306405D01*
X690445Y-305906D01*
X689945Y-305406D01*
Y-304906D01*
X690445Y-305906D02*
X691445D01*
X692944Y-304906D02*
X693444Y-304406D01*
X694444D01*
X694944Y-304906D01*
Y-306905D01*
X694444Y-307405D01*
X693444D01*
X692944Y-306905D01*
Y-304906D01*
X686946Y-302681D02*
Y-299682D01*
X688446D01*
X688945Y-300181D01*
Y-301181D01*
X688446Y-301681D01*
X686946D01*
X687946D02*
X688945Y-302681D01*
X689945Y-299682D02*
X691945D01*
Y-300181D01*
X689945Y-302181D01*
Y-302681D01*
X692944Y-302181D02*
X693444Y-302681D01*
X694444D01*
X694944Y-302181D01*
Y-300181D01*
X694444Y-299682D01*
X693444D01*
X692944Y-300181D01*
Y-300681D01*
X693444Y-301181D01*
X694944D01*
X533009Y-283783D02*
Y-280784D01*
X534509D01*
X535008Y-281284D01*
Y-282283D01*
X534509Y-282783D01*
X533009D01*
X534009D02*
X535008Y-283783D01*
X536008Y-280784D02*
X538007D01*
Y-281284D01*
X536008Y-283283D01*
Y-283783D01*
X539007Y-281284D02*
X539507Y-280784D01*
X540507D01*
X541007Y-281284D01*
Y-281784D01*
X540507Y-282283D01*
X541007Y-282783D01*
Y-283283D01*
X540507Y-283783D01*
X539507D01*
X539007Y-283283D01*
Y-282783D01*
X539507Y-282283D01*
X539007Y-281784D01*
Y-281284D01*
X539507Y-282283D02*
X540507D01*
X548350Y-255180D02*
X545351D01*
Y-253680D01*
X545851Y-253181D01*
X546850D01*
X547350Y-253680D01*
Y-255180D01*
Y-254180D02*
X548350Y-253181D01*
X545351Y-252181D02*
Y-250181D01*
X545851D01*
X547850Y-252181D01*
X548350D01*
X545351Y-247182D02*
X545851Y-248182D01*
X546850Y-249182D01*
X547850D01*
X548350Y-248682D01*
Y-247682D01*
X547850Y-247182D01*
X547350D01*
X546850Y-247682D01*
Y-249182D01*
X578285Y-295594D02*
Y-292595D01*
X579784D01*
X580284Y-293095D01*
Y-294094D01*
X579784Y-294594D01*
X578285D01*
X579284D02*
X580284Y-295594D01*
X581284Y-292595D02*
X583283D01*
Y-293095D01*
X581284Y-295094D01*
Y-295594D01*
X586282Y-292595D02*
X584283D01*
Y-294094D01*
X585283Y-293595D01*
X585782D01*
X586282Y-294094D01*
Y-295094D01*
X585782Y-295594D01*
X584783D01*
X584283Y-295094D01*
X532616Y-303074D02*
Y-300075D01*
X534115D01*
X534615Y-300575D01*
Y-301575D01*
X534115Y-302075D01*
X532616D01*
X533615D02*
X534615Y-303074D01*
X535614Y-300075D02*
X537614D01*
Y-300575D01*
X535614Y-302574D01*
Y-303074D01*
X540113D02*
Y-300075D01*
X538614Y-301575D01*
X540613D01*
X591808Y-271198D02*
X594807D01*
Y-272698D01*
X594307Y-273198D01*
X593307D01*
X592807Y-272698D01*
Y-271198D01*
Y-272198D02*
X591808Y-273198D01*
X594807Y-274197D02*
Y-276197D01*
X594307D01*
X592307Y-274197D01*
X591808D01*
X594307Y-277196D02*
X594807Y-277696D01*
Y-278696D01*
X594307Y-279196D01*
X593807D01*
X593307Y-278696D01*
Y-278196D01*
Y-278696D01*
X592807Y-279196D01*
X592307D01*
X591808Y-278696D01*
Y-277696D01*
X592307Y-277196D01*
X646789Y-276303D02*
Y-273304D01*
X648288D01*
X648788Y-273803D01*
Y-274803D01*
X648288Y-275303D01*
X646789D01*
X647788D02*
X648788Y-276303D01*
X649788Y-273304D02*
X651787D01*
Y-273803D01*
X649788Y-275803D01*
Y-276303D01*
X654786D02*
X652787D01*
X654786Y-274303D01*
Y-273803D01*
X654286Y-273304D01*
X653287D01*
X652787Y-273803D01*
X578391Y-299925D02*
Y-296926D01*
X579890D01*
X580390Y-297426D01*
Y-298425D01*
X579890Y-298925D01*
X578391D01*
X579391D02*
X580390Y-299925D01*
X581390Y-296926D02*
X583389D01*
Y-297426D01*
X581390Y-299425D01*
Y-299925D01*
X584389D02*
X585389D01*
X584889D01*
Y-296926D01*
X584389Y-297426D01*
X556238Y-299925D02*
Y-296926D01*
X557737D01*
X558237Y-297426D01*
Y-298425D01*
X557737Y-298925D01*
X556238D01*
X557237D02*
X558237Y-299925D01*
X559236Y-296926D02*
X561236D01*
Y-297426D01*
X559236Y-299425D01*
Y-299925D01*
X562236Y-297426D02*
X562735Y-296926D01*
X563735D01*
X564235Y-297426D01*
Y-299425D01*
X563735Y-299925D01*
X562735D01*
X562236Y-299425D01*
Y-297426D01*
X610705Y-293639D02*
X613704D01*
Y-295139D01*
X613204Y-295638D01*
X612205D01*
X611705Y-295139D01*
Y-293639D01*
Y-294639D02*
X610705Y-295638D01*
X613704Y-298638D02*
X613204Y-297638D01*
X612205Y-296638D01*
X611205D01*
X610705Y-297138D01*
Y-298138D01*
X611205Y-298638D01*
X611705D01*
X612205Y-298138D01*
Y-296638D01*
X611205Y-299637D02*
X610705Y-300137D01*
Y-301137D01*
X611205Y-301637D01*
X613204D01*
X613704Y-301137D01*
Y-300137D01*
X613204Y-299637D01*
X612705D01*
X612205Y-300137D01*
Y-301637D01*
X533009Y-288507D02*
Y-285508D01*
X534509D01*
X535008Y-286008D01*
Y-287008D01*
X534509Y-287508D01*
X533009D01*
X534009D02*
X535008Y-288507D01*
X538007Y-285508D02*
X537008Y-286008D01*
X536008Y-287008D01*
Y-288007D01*
X536508Y-288507D01*
X537508D01*
X538007Y-288007D01*
Y-287508D01*
X537508Y-287008D01*
X536008D01*
X539007Y-286008D02*
X539507Y-285508D01*
X540507D01*
X541007Y-286008D01*
Y-286508D01*
X540507Y-287008D01*
X541007Y-287508D01*
Y-288007D01*
X540507Y-288507D01*
X539507D01*
X539007Y-288007D01*
Y-287508D01*
X539507Y-287008D01*
X539007Y-286508D01*
Y-286008D01*
X539507Y-287008D02*
X540507D01*
X533009Y-293625D02*
Y-290627D01*
X534509D01*
X535008Y-291126D01*
Y-292126D01*
X534509Y-292626D01*
X533009D01*
X534009D02*
X535008Y-293625D01*
X538007Y-290627D02*
X537008Y-291126D01*
X536008Y-292126D01*
Y-293126D01*
X536508Y-293625D01*
X537508D01*
X538007Y-293126D01*
Y-292626D01*
X537508Y-292126D01*
X536008D01*
X539007Y-290627D02*
X541007D01*
Y-291126D01*
X539007Y-293126D01*
Y-293625D01*
X671592Y-247563D02*
Y-244564D01*
X673091D01*
X673591Y-245063D01*
Y-246063D01*
X673091Y-246563D01*
X671592D01*
X672591D02*
X673591Y-247563D01*
X676590Y-244564D02*
X675591Y-245063D01*
X674591Y-246063D01*
Y-247063D01*
X675091Y-247563D01*
X676090D01*
X676590Y-247063D01*
Y-246563D01*
X676090Y-246063D01*
X674591D01*
X679589Y-244564D02*
X678590Y-245063D01*
X677590Y-246063D01*
Y-247063D01*
X678090Y-247563D01*
X679089D01*
X679589Y-247063D01*
Y-246563D01*
X679089Y-246063D01*
X677590D01*
X661493Y-240096D02*
X664492D01*
Y-241595D01*
X663992Y-242095D01*
X662992D01*
X662492Y-241595D01*
Y-240096D01*
Y-241095D02*
X661493Y-242095D01*
X664492Y-245094D02*
X663992Y-244094D01*
X662992Y-243095D01*
X661993D01*
X661493Y-243595D01*
Y-244594D01*
X661993Y-245094D01*
X662492D01*
X662992Y-244594D01*
Y-243095D01*
X664492Y-248093D02*
Y-246094D01*
X662992D01*
X663492Y-247094D01*
Y-247593D01*
X662992Y-248093D01*
X661993D01*
X661493Y-247593D01*
Y-246594D01*
X661993Y-246094D01*
X560175Y-106224D02*
Y-103225D01*
X561674D01*
X562174Y-103725D01*
Y-104724D01*
X561674Y-105224D01*
X560175D01*
X561174D02*
X562174Y-106224D01*
X565173Y-103225D02*
X564173Y-103725D01*
X563174Y-104724D01*
Y-105724D01*
X563673Y-106224D01*
X564673D01*
X565173Y-105724D01*
Y-105224D01*
X564673Y-104724D01*
X563174D01*
X567672Y-106224D02*
Y-103225D01*
X566173Y-104724D01*
X568172D01*
X546395Y-197169D02*
Y-194170D01*
X547894D01*
X548394Y-194670D01*
Y-195669D01*
X547894Y-196169D01*
X546395D01*
X547395D02*
X548394Y-197169D01*
X551393Y-194170D02*
X550394Y-194670D01*
X549394Y-195669D01*
Y-196669D01*
X549894Y-197169D01*
X550893D01*
X551393Y-196669D01*
Y-196169D01*
X550893Y-195669D01*
X549394D01*
X552393Y-194670D02*
X552893Y-194170D01*
X553893D01*
X554392Y-194670D01*
Y-195169D01*
X553893Y-195669D01*
X553393D01*
X553893D01*
X554392Y-196169D01*
Y-196669D01*
X553893Y-197169D01*
X552893D01*
X552393Y-196669D01*
X547182Y-104255D02*
Y-101256D01*
X548682D01*
X549182Y-101756D01*
Y-102756D01*
X548682Y-103256D01*
X547182D01*
X548182D02*
X549182Y-104255D01*
X552181Y-101256D02*
X551181Y-101756D01*
X550181Y-102756D01*
Y-103756D01*
X550681Y-104255D01*
X551681D01*
X552181Y-103756D01*
Y-103256D01*
X551681Y-102756D01*
X550181D01*
X555180Y-104255D02*
X553181D01*
X555180Y-102256D01*
Y-101756D01*
X554680Y-101256D01*
X553680D01*
X553181Y-101756D01*
X568429Y-194444D02*
X565430D01*
Y-192944D01*
X565929Y-192444D01*
X566929D01*
X567429Y-192944D01*
Y-194444D01*
Y-193444D02*
X568429Y-192444D01*
X565430Y-189445D02*
X565929Y-190445D01*
X566929Y-191445D01*
X567929D01*
X568429Y-190945D01*
Y-189945D01*
X567929Y-189445D01*
X567429D01*
X566929Y-189945D01*
Y-191445D01*
X568429Y-188446D02*
Y-187446D01*
Y-187946D01*
X565430D01*
X565929Y-188446D01*
X602361Y-221772D02*
Y-218773D01*
X603861D01*
X604361Y-219273D01*
Y-220272D01*
X603861Y-220772D01*
X602361D01*
X603361D02*
X604361Y-221772D01*
X607360Y-218773D02*
X606360Y-219273D01*
X605360Y-220272D01*
Y-221272D01*
X605860Y-221772D01*
X606860D01*
X607360Y-221272D01*
Y-220772D01*
X606860Y-220272D01*
X605360D01*
X608359Y-219273D02*
X608859Y-218773D01*
X609859D01*
X610359Y-219273D01*
Y-221272D01*
X609859Y-221772D01*
X608859D01*
X608359Y-221272D01*
Y-219273D01*
X550318Y-217778D02*
X547319D01*
Y-216279D01*
X547819Y-215779D01*
X548819D01*
X549319Y-216279D01*
Y-217778D01*
Y-216778D02*
X550318Y-215779D01*
X547319Y-212780D02*
Y-214779D01*
X548819D01*
X548319Y-213779D01*
Y-213280D01*
X548819Y-212780D01*
X549819D01*
X550318Y-213280D01*
Y-214279D01*
X549819Y-214779D01*
Y-211780D02*
X550318Y-211280D01*
Y-210281D01*
X549819Y-209781D01*
X547819D01*
X547319Y-210281D01*
Y-211280D01*
X547819Y-211780D01*
X548319D01*
X548819Y-211280D01*
Y-209781D01*
X636008Y-296881D02*
X635508Y-297381D01*
Y-298381D01*
X636008Y-298881D01*
X638007D01*
X638507Y-298381D01*
Y-297381D01*
X638007Y-296881D01*
X636008Y-295882D02*
X635508Y-295382D01*
Y-294382D01*
X636008Y-293882D01*
X636508D01*
X637008Y-294382D01*
X637508Y-293882D01*
X638007D01*
X638507Y-294382D01*
Y-295382D01*
X638007Y-295882D01*
X637508D01*
X637008Y-295382D01*
X636508Y-295882D01*
X636008D01*
X637008Y-295382D02*
Y-294382D01*
X635508Y-290883D02*
Y-292882D01*
X637008D01*
X636508Y-291883D01*
Y-291383D01*
X637008Y-290883D01*
X638007D01*
X638507Y-291383D01*
Y-292383D01*
X638007Y-292882D01*
X672410Y-282859D02*
X671910Y-282359D01*
X670911D01*
X670411Y-282859D01*
Y-284858D01*
X670911Y-285358D01*
X671910D01*
X672410Y-284858D01*
X673410Y-282859D02*
X673910Y-282359D01*
X674909D01*
X675409Y-282859D01*
Y-283358D01*
X674909Y-283858D01*
X675409Y-284358D01*
Y-284858D01*
X674909Y-285358D01*
X673910D01*
X673410Y-284858D01*
Y-284358D01*
X673910Y-283858D01*
X673410Y-283358D01*
Y-282859D01*
X673910Y-283858D02*
X674909D01*
X677908Y-285358D02*
Y-282359D01*
X676409Y-283858D01*
X678408D01*
X632253Y-276953D02*
X631753Y-276453D01*
X630753D01*
X630253Y-276953D01*
Y-278952D01*
X630753Y-279452D01*
X631753D01*
X632253Y-278952D01*
X633252Y-276953D02*
X633752Y-276453D01*
X634752D01*
X635252Y-276953D01*
Y-277453D01*
X634752Y-277953D01*
X635252Y-278453D01*
Y-278952D01*
X634752Y-279452D01*
X633752D01*
X633252Y-278952D01*
Y-278453D01*
X633752Y-277953D01*
X633252Y-277453D01*
Y-276953D01*
X633752Y-277953D02*
X634752D01*
X636251Y-276953D02*
X636751Y-276453D01*
X637751D01*
X638251Y-276953D01*
Y-277453D01*
X637751Y-277953D01*
X637251D01*
X637751D01*
X638251Y-278453D01*
Y-278952D01*
X637751Y-279452D01*
X636751D01*
X636251Y-278952D01*
X671623Y-275378D02*
X671123Y-274878D01*
X670123D01*
X669623Y-275378D01*
Y-277378D01*
X670123Y-277877D01*
X671123D01*
X671623Y-277378D01*
X672622Y-275378D02*
X673122Y-274878D01*
X674122D01*
X674622Y-275378D01*
Y-275878D01*
X674122Y-276378D01*
X674622Y-276878D01*
Y-277378D01*
X674122Y-277877D01*
X673122D01*
X672622Y-277378D01*
Y-276878D01*
X673122Y-276378D01*
X672622Y-275878D01*
Y-275378D01*
X673122Y-276378D02*
X674122D01*
X677621Y-277877D02*
X675621D01*
X677621Y-275878D01*
Y-275378D01*
X677121Y-274878D01*
X676121D01*
X675621Y-275378D01*
X672910Y-251362D02*
X672410Y-250863D01*
X671410D01*
X670911Y-251362D01*
Y-253362D01*
X671410Y-253862D01*
X672410D01*
X672910Y-253362D01*
X673910Y-251362D02*
X674409Y-250863D01*
X675409D01*
X675909Y-251362D01*
Y-251862D01*
X675409Y-252362D01*
X675909Y-252862D01*
Y-253362D01*
X675409Y-253862D01*
X674409D01*
X673910Y-253362D01*
Y-252862D01*
X674409Y-252362D01*
X673910Y-251862D01*
Y-251362D01*
X674409Y-252362D02*
X675409D01*
X676909Y-253862D02*
X677908D01*
X677409D01*
Y-250863D01*
X676909Y-251362D01*
X672804Y-259630D02*
X672304Y-259130D01*
X671304D01*
X670804Y-259630D01*
Y-261630D01*
X671304Y-262129D01*
X672304D01*
X672804Y-261630D01*
X673804Y-259630D02*
X674303Y-259130D01*
X675303D01*
X675803Y-259630D01*
Y-260130D01*
X675303Y-260630D01*
X675803Y-261130D01*
Y-261630D01*
X675303Y-262129D01*
X674303D01*
X673804Y-261630D01*
Y-261130D01*
X674303Y-260630D01*
X673804Y-260130D01*
Y-259630D01*
X674303Y-260630D02*
X675303D01*
X676802Y-259630D02*
X677302Y-259130D01*
X678302D01*
X678802Y-259630D01*
Y-261630D01*
X678302Y-262129D01*
X677302D01*
X676802Y-261630D01*
Y-259630D01*
X651938Y-241520D02*
X651438Y-241020D01*
X650438D01*
X649938Y-241520D01*
Y-243519D01*
X650438Y-244019D01*
X651438D01*
X651938Y-243519D01*
X652937Y-241020D02*
X654937D01*
Y-241520D01*
X652937Y-243519D01*
Y-244019D01*
X655936Y-243519D02*
X656436Y-244019D01*
X657436D01*
X657936Y-243519D01*
Y-241520D01*
X657436Y-241020D01*
X656436D01*
X655936Y-241520D01*
Y-242020D01*
X656436Y-242520D01*
X657936D01*
X677135Y-268292D02*
X676635Y-267792D01*
X675635D01*
X675135Y-268292D01*
Y-270291D01*
X675635Y-270791D01*
X676635D01*
X677135Y-270291D01*
X678134Y-267792D02*
X680133D01*
Y-268292D01*
X678134Y-270291D01*
Y-270791D01*
X681133Y-268292D02*
X681633Y-267792D01*
X682633D01*
X683133Y-268292D01*
Y-268792D01*
X682633Y-269291D01*
X683133Y-269791D01*
Y-270291D01*
X682633Y-270791D01*
X681633D01*
X681133Y-270291D01*
Y-269791D01*
X681633Y-269291D01*
X681133Y-268792D01*
Y-268292D01*
X681633Y-269291D02*
X682633D01*
X583140Y-254595D02*
X582640Y-255095D01*
Y-256095D01*
X583140Y-256595D01*
X585139D01*
X585639Y-256095D01*
Y-255095D01*
X585139Y-254595D01*
X582640Y-253596D02*
Y-251596D01*
X583140D01*
X585139Y-253596D01*
X585639D01*
X582640Y-250596D02*
Y-248597D01*
X583140D01*
X585139Y-250596D01*
X585639D01*
X594163Y-254989D02*
X593663Y-255489D01*
Y-256488D01*
X594163Y-256988D01*
X596162D01*
X596662Y-256488D01*
Y-255489D01*
X596162Y-254989D01*
X593663Y-253989D02*
Y-251990D01*
X594163D01*
X596162Y-253989D01*
X596662D01*
X593663Y-248991D02*
X594163Y-249991D01*
X595163Y-250990D01*
X596162D01*
X596662Y-250490D01*
Y-249491D01*
X596162Y-248991D01*
X595663D01*
X595163Y-249491D01*
Y-250990D01*
X592403Y-242030D02*
X592903Y-241530D01*
Y-240530D01*
X592403Y-240031D01*
X590404D01*
X589904Y-240530D01*
Y-241530D01*
X590404Y-242030D01*
X592903Y-243030D02*
Y-245029D01*
X592403D01*
X590404Y-243030D01*
X589904D01*
X592903Y-248028D02*
Y-246029D01*
X591403D01*
X591903Y-247028D01*
Y-247528D01*
X591403Y-248028D01*
X590404D01*
X589904Y-247528D01*
Y-246529D01*
X590404Y-246029D01*
X574440Y-298638D02*
X574940Y-299137D01*
X575940D01*
X576440Y-298638D01*
Y-296638D01*
X575940Y-296138D01*
X574940D01*
X574440Y-296638D01*
X573441Y-299137D02*
X571441D01*
Y-298638D01*
X573441Y-296638D01*
Y-296138D01*
X568942D02*
Y-299137D01*
X570442Y-297638D01*
X568442D01*
X541126Y-261054D02*
X540626Y-261554D01*
Y-262554D01*
X541126Y-263054D01*
X543126D01*
X543625Y-262554D01*
Y-261554D01*
X543126Y-261054D01*
X540626Y-260055D02*
Y-258055D01*
X541126D01*
X543126Y-260055D01*
X543625D01*
X541126Y-257056D02*
X540626Y-256556D01*
Y-255556D01*
X541126Y-255056D01*
X541626D01*
X542126Y-255556D01*
Y-256056D01*
Y-255556D01*
X542626Y-255056D01*
X543126D01*
X543625Y-255556D01*
Y-256556D01*
X543126Y-257056D01*
X592338Y-297607D02*
X592838Y-297107D01*
Y-296107D01*
X592338Y-295608D01*
X590339D01*
X589839Y-296107D01*
Y-297107D01*
X590339Y-297607D01*
X592838Y-298607D02*
Y-300606D01*
X592338D01*
X590339Y-298607D01*
X589839D01*
Y-303605D02*
Y-301606D01*
X591838Y-303605D01*
X592338D01*
X592838Y-303105D01*
Y-302105D01*
X592338Y-301606D01*
X534721Y-295851D02*
X534221Y-295351D01*
X533221D01*
X532722Y-295851D01*
Y-297850D01*
X533221Y-298350D01*
X534221D01*
X534721Y-297850D01*
X535721Y-295351D02*
X537720D01*
Y-295851D01*
X535721Y-297850D01*
Y-298350D01*
X538720D02*
X539719D01*
X539220D01*
Y-295351D01*
X538720Y-295851D01*
X557843Y-301756D02*
X557343Y-301256D01*
X556344D01*
X555844Y-301756D01*
Y-303756D01*
X556344Y-304255D01*
X557343D01*
X557843Y-303756D01*
X558843Y-301256D02*
X560842D01*
Y-301756D01*
X558843Y-303756D01*
Y-304255D01*
X561842Y-301756D02*
X562342Y-301256D01*
X563341D01*
X563841Y-301756D01*
Y-303756D01*
X563341Y-304255D01*
X562342D01*
X561842Y-303756D01*
Y-301756D01*
X534615Y-304118D02*
X534115Y-303619D01*
X533115D01*
X532616Y-304118D01*
Y-306118D01*
X533115Y-306618D01*
X534115D01*
X534615Y-306118D01*
X537614Y-303619D02*
X536614Y-304118D01*
X535614Y-305118D01*
Y-306118D01*
X536114Y-306618D01*
X537114D01*
X537614Y-306118D01*
Y-305618D01*
X537114Y-305118D01*
X535614D01*
X538614Y-306118D02*
X539113Y-306618D01*
X540113D01*
X540613Y-306118D01*
Y-304118D01*
X540113Y-303619D01*
X539113D01*
X538614Y-304118D01*
Y-304618D01*
X539113Y-305118D01*
X540613D01*
X603181Y-302968D02*
X603680Y-303468D01*
X604680D01*
X605180Y-302968D01*
Y-300969D01*
X604680Y-300469D01*
X603680D01*
X603181Y-300969D01*
X600181Y-303468D02*
X601181Y-302968D01*
X602181Y-301969D01*
Y-300969D01*
X601681Y-300469D01*
X600681D01*
X600181Y-300969D01*
Y-301469D01*
X600681Y-301969D01*
X602181D01*
X599182Y-302968D02*
X598682Y-303468D01*
X597682D01*
X597182Y-302968D01*
Y-302468D01*
X597682Y-301969D01*
X597182Y-301469D01*
Y-300969D01*
X597682Y-300469D01*
X598682D01*
X599182Y-300969D01*
Y-301469D01*
X598682Y-301969D01*
X599182Y-302468D01*
Y-302968D01*
X598682Y-301969D02*
X597682D01*
X503619Y-96001D02*
X506618D01*
Y-97501D01*
X506118Y-98001D01*
X505118D01*
X504618Y-97501D01*
Y-96001D01*
Y-97001D02*
X503619Y-98001D01*
X506618Y-101000D02*
Y-99000D01*
X505118D01*
X505618Y-100000D01*
Y-100500D01*
X505118Y-101000D01*
X504118D01*
X503619Y-100500D01*
Y-99500D01*
X504118Y-99000D01*
X506118Y-101999D02*
X506618Y-102499D01*
Y-103499D01*
X506118Y-103999D01*
X505618D01*
X505118Y-103499D01*
X504618Y-103999D01*
X504118D01*
X503619Y-103499D01*
Y-102499D01*
X504118Y-101999D01*
X504618D01*
X505118Y-102499D01*
X505618Y-101999D01*
X506118D01*
X505118Y-102499D02*
Y-103499D01*
X507949Y-96789D02*
X510948D01*
Y-98288D01*
X510449Y-98788D01*
X509449D01*
X508949Y-98288D01*
Y-96789D01*
Y-97788D02*
X507949Y-98788D01*
X510948Y-101787D02*
Y-99788D01*
X509449D01*
X509949Y-100787D01*
Y-101287D01*
X509449Y-101787D01*
X508449D01*
X507949Y-101287D01*
Y-100288D01*
X508449Y-99788D01*
X510948Y-102787D02*
Y-104786D01*
X510449D01*
X508449Y-102787D01*
X507949D01*
X470791Y-128408D02*
X467792D01*
Y-126909D01*
X468292Y-126409D01*
X469291D01*
X469791Y-126909D01*
Y-128408D01*
Y-127409D02*
X470791Y-126409D01*
X467792Y-123410D02*
Y-125409D01*
X469291D01*
X468791Y-124409D01*
Y-123910D01*
X469291Y-123410D01*
X470291D01*
X470791Y-123910D01*
Y-124909D01*
X470291Y-125409D01*
X467792Y-120411D02*
X468292Y-121410D01*
X469291Y-122410D01*
X470291D01*
X470791Y-121910D01*
Y-120911D01*
X470291Y-120411D01*
X469791D01*
X469291Y-120911D01*
Y-122410D01*
X485371Y-103862D02*
Y-100863D01*
X486871D01*
X487371Y-101363D01*
Y-102362D01*
X486871Y-102862D01*
X485371D01*
X486371D02*
X487371Y-103862D01*
X490370Y-100863D02*
X488370D01*
Y-102362D01*
X489370Y-101862D01*
X489870D01*
X490370Y-102362D01*
Y-103362D01*
X489870Y-103862D01*
X488870D01*
X488370Y-103362D01*
X493369Y-100863D02*
X491369D01*
Y-102362D01*
X492369Y-101862D01*
X492869D01*
X493369Y-102362D01*
Y-103362D01*
X492869Y-103862D01*
X491869D01*
X491369Y-103362D01*
X464899Y-103862D02*
Y-100863D01*
X466398D01*
X466898Y-101363D01*
Y-102362D01*
X466398Y-102862D01*
X464899D01*
X465899D02*
X466898Y-103862D01*
X469897Y-100863D02*
X467898D01*
Y-102362D01*
X468898Y-101862D01*
X469397D01*
X469897Y-102362D01*
Y-103362D01*
X469397Y-103862D01*
X468398D01*
X467898Y-103362D01*
X472397Y-103862D02*
Y-100863D01*
X470897Y-102362D01*
X472896D01*
X466867Y-114098D02*
Y-111099D01*
X468367D01*
X468867Y-111599D01*
Y-112598D01*
X468367Y-113098D01*
X466867D01*
X467867D02*
X468867Y-114098D01*
X471866Y-111099D02*
X469867D01*
Y-112598D01*
X470866Y-112099D01*
X471366D01*
X471866Y-112598D01*
Y-113598D01*
X471366Y-114098D01*
X470366D01*
X469867Y-113598D01*
X472865Y-111599D02*
X473365Y-111099D01*
X474365D01*
X474865Y-111599D01*
Y-112099D01*
X474365Y-112598D01*
X473865D01*
X474365D01*
X474865Y-113098D01*
Y-113598D01*
X474365Y-114098D01*
X473365D01*
X472865Y-113598D01*
X475529Y-103862D02*
Y-100863D01*
X477028D01*
X477528Y-101363D01*
Y-102362D01*
X477028Y-102862D01*
X475529D01*
X476529D02*
X477528Y-103862D01*
X480527Y-100863D02*
X478528D01*
Y-102362D01*
X479528Y-101862D01*
X480027D01*
X480527Y-102362D01*
Y-103362D01*
X480027Y-103862D01*
X479028D01*
X478528Y-103362D01*
X483526Y-103862D02*
X481527D01*
X483526Y-101862D01*
Y-101363D01*
X483026Y-100863D01*
X482027D01*
X481527Y-101363D01*
X502013Y-118035D02*
Y-115036D01*
X503512D01*
X504012Y-115536D01*
Y-116535D01*
X503512Y-117035D01*
X502013D01*
X503013D02*
X504012Y-118035D01*
X507011Y-115036D02*
X505012D01*
Y-116535D01*
X506012Y-116036D01*
X506511D01*
X507011Y-116535D01*
Y-117535D01*
X506511Y-118035D01*
X505512D01*
X505012Y-117535D01*
X508011Y-118035D02*
X509011D01*
X508511D01*
Y-115036D01*
X508011Y-115536D01*
X470411Y-140476D02*
Y-137477D01*
X471910D01*
X472410Y-137977D01*
Y-138976D01*
X471910Y-139476D01*
X470411D01*
X471410D02*
X472410Y-140476D01*
X475409Y-137477D02*
X473410D01*
Y-138976D01*
X474409Y-138477D01*
X474909D01*
X475409Y-138976D01*
Y-139976D01*
X474909Y-140476D01*
X473910D01*
X473410Y-139976D01*
X476409Y-137977D02*
X476909Y-137477D01*
X477908D01*
X478408Y-137977D01*
Y-139976D01*
X477908Y-140476D01*
X476909D01*
X476409Y-139976D01*
Y-137977D01*
X506874Y-127590D02*
X506375Y-128090D01*
Y-129089D01*
X506874Y-129589D01*
X508874D01*
X509374Y-129089D01*
Y-128090D01*
X508874Y-127590D01*
X506375Y-124591D02*
X506874Y-125591D01*
X507874Y-126590D01*
X508874D01*
X509374Y-126090D01*
Y-125091D01*
X508874Y-124591D01*
X508374D01*
X507874Y-125091D01*
Y-126590D01*
X506375Y-123591D02*
Y-121592D01*
X506874D01*
X508874Y-123591D01*
X509374D01*
X509812Y-133646D02*
X509312Y-133146D01*
X508312D01*
X507812Y-133646D01*
Y-135645D01*
X508312Y-136145D01*
X509312D01*
X509812Y-135645D01*
X512811Y-133146D02*
X511811Y-133646D01*
X510811Y-134646D01*
Y-135645D01*
X511311Y-136145D01*
X512311D01*
X512811Y-135645D01*
Y-135145D01*
X512311Y-134646D01*
X510811D01*
X515810Y-133146D02*
X514810Y-133646D01*
X513810Y-134646D01*
Y-135645D01*
X514310Y-136145D01*
X515310D01*
X515810Y-135645D01*
Y-135145D01*
X515310Y-134646D01*
X513810D01*
X496426Y-101363D02*
X495926Y-100863D01*
X494926D01*
X494426Y-101363D01*
Y-103362D01*
X494926Y-103862D01*
X495926D01*
X496426Y-103362D01*
X499425Y-100863D02*
X498425Y-101363D01*
X497426Y-102362D01*
Y-103362D01*
X497925Y-103862D01*
X498925D01*
X499425Y-103362D01*
Y-102862D01*
X498925Y-102362D01*
X497426D01*
X502424Y-100863D02*
X500425D01*
Y-102362D01*
X501424Y-101862D01*
X501924D01*
X502424Y-102362D01*
Y-103362D01*
X501924Y-103862D01*
X500924D01*
X500425Y-103362D01*
X666898Y-40339D02*
X666398Y-39839D01*
X665399D01*
X664899Y-40339D01*
Y-42338D01*
X665399Y-42838D01*
X666398D01*
X666898Y-42338D01*
X669897Y-39839D02*
X668898Y-40339D01*
X667898Y-41339D01*
Y-42338D01*
X668398Y-42838D01*
X669397D01*
X669897Y-42338D01*
Y-41838D01*
X669397Y-41339D01*
X667898D01*
X672397Y-42838D02*
Y-39839D01*
X670897Y-41339D01*
X672896D01*
X591701Y-44276D02*
X591202Y-43776D01*
X590202D01*
X589702Y-44276D01*
Y-46275D01*
X590202Y-46775D01*
X591202D01*
X591701Y-46275D01*
X594700Y-43776D02*
X592701D01*
Y-45276D01*
X593701Y-44776D01*
X594201D01*
X594700Y-45276D01*
Y-46275D01*
X594201Y-46775D01*
X593201D01*
X592701Y-46275D01*
X595700Y-43776D02*
X597699D01*
Y-44276D01*
X595700Y-46275D01*
Y-46775D01*
X668473Y-62386D02*
X667973Y-61886D01*
X666974D01*
X666474Y-62386D01*
Y-64385D01*
X666974Y-64885D01*
X667973D01*
X668473Y-64385D01*
X671472Y-61886D02*
X669473D01*
Y-63386D01*
X670472Y-62886D01*
X670972D01*
X671472Y-63386D01*
Y-64385D01*
X670972Y-64885D01*
X669973D01*
X669473Y-64385D01*
X674471Y-61886D02*
X673471Y-62386D01*
X672472Y-63386D01*
Y-64385D01*
X672972Y-64885D01*
X673971D01*
X674471Y-64385D01*
Y-63886D01*
X673971Y-63386D01*
X672472D01*
X607511Y-62417D02*
X608011Y-62917D01*
X609011D01*
X609511Y-62417D01*
Y-60418D01*
X609011Y-59918D01*
X608011D01*
X607511Y-60418D01*
X604512Y-62917D02*
X606511D01*
Y-61417D01*
X605512Y-61917D01*
X605012D01*
X604512Y-61417D01*
Y-60418D01*
X605012Y-59918D01*
X606012D01*
X606511Y-60418D01*
X601513Y-62917D02*
X603512D01*
Y-61417D01*
X602513Y-61917D01*
X602013D01*
X601513Y-61417D01*
Y-60418D01*
X602013Y-59918D01*
X603013D01*
X603512Y-60418D01*
X57299Y-25560D02*
X57799Y-25060D01*
Y-24060D01*
X57299Y-23560D01*
X55300D01*
X54800Y-24060D01*
Y-25060D01*
X55300Y-25560D01*
X57799Y-28559D02*
Y-26559D01*
X56299D01*
X56799Y-27559D01*
Y-28059D01*
X56299Y-28559D01*
X55300D01*
X54800Y-28059D01*
Y-27059D01*
X55300Y-26559D01*
X54800Y-31058D02*
X57799D01*
X56299Y-29558D01*
Y-31558D01*
X111630Y-25953D02*
X112129Y-25454D01*
Y-24454D01*
X111630Y-23954D01*
X109630D01*
X109130Y-24454D01*
Y-25454D01*
X109630Y-25953D01*
X109130Y-28453D02*
X112129D01*
X110630Y-26953D01*
Y-28952D01*
X111630Y-29952D02*
X112129Y-30452D01*
Y-31452D01*
X111630Y-31951D01*
X111130D01*
X110630Y-31452D01*
Y-30952D01*
Y-31452D01*
X110130Y-31951D01*
X109630D01*
X109130Y-31452D01*
Y-30452D01*
X109630Y-29952D01*
X39158Y-41369D02*
X38658Y-41869D01*
Y-42869D01*
X39158Y-43369D01*
X41157D01*
X41657Y-42869D01*
Y-41869D01*
X41157Y-41369D01*
X41657Y-38870D02*
X38658D01*
X40157Y-40370D01*
Y-38370D01*
X41657Y-35371D02*
Y-37371D01*
X39658Y-35371D01*
X39158D01*
X38658Y-35871D01*
Y-36871D01*
X39158Y-37371D01*
X125409Y-26059D02*
X125909Y-25560D01*
Y-24560D01*
X125409Y-24060D01*
X123410D01*
X122910Y-24560D01*
Y-25560D01*
X123410Y-26059D01*
X122910Y-28559D02*
X125909D01*
X124409Y-27059D01*
Y-29059D01*
X122910Y-30058D02*
Y-31058D01*
Y-30558D01*
X125909D01*
X125409Y-30058D01*
X429466Y-186145D02*
Y-183146D01*
X430965D01*
X431465Y-183646D01*
Y-184646D01*
X430965Y-185145D01*
X429466D01*
X430466D02*
X431465Y-186145D01*
X433964D02*
Y-183146D01*
X432465Y-184646D01*
X434464D01*
X435464Y-185645D02*
X435964Y-186145D01*
X436964D01*
X437463Y-185645D01*
Y-183646D01*
X436964Y-183146D01*
X435964D01*
X435464Y-183646D01*
Y-184146D01*
X435964Y-184646D01*
X437463D01*
X134327Y-126710D02*
X137326D01*
Y-128209D01*
X136826Y-128709D01*
X135827D01*
X135327Y-128209D01*
Y-126710D01*
Y-127710D02*
X134327Y-128709D01*
Y-131209D02*
X137326D01*
X135827Y-129709D01*
Y-131708D01*
X136826Y-132708D02*
X137326Y-133208D01*
Y-134207D01*
X136826Y-134707D01*
X136327D01*
X135827Y-134207D01*
X135327Y-134707D01*
X134827D01*
X134327Y-134207D01*
Y-133208D01*
X134827Y-132708D01*
X135327D01*
X135827Y-133208D01*
X136327Y-132708D01*
X136826D01*
X135827Y-133208D02*
Y-134207D01*
X238559Y-339551D02*
X238059Y-339052D01*
X237059D01*
X236559Y-339551D01*
Y-340051D01*
X237059Y-340551D01*
X238059D01*
X238559Y-341051D01*
Y-341551D01*
X238059Y-342051D01*
X237059D01*
X236559Y-341551D01*
X239558Y-339052D02*
Y-342051D01*
Y-341051D01*
X241558Y-339052D01*
X240058Y-340551D01*
X241558Y-342051D01*
X242557Y-339052D02*
X244557D01*
X243557D01*
Y-342051D01*
X245556D02*
X246556D01*
X246056D01*
Y-339052D01*
X245556Y-339551D01*
X248056D02*
X248555Y-339052D01*
X249555D01*
X250055Y-339551D01*
Y-341551D01*
X249555Y-342051D01*
X248555D01*
X248056Y-341551D01*
Y-339551D01*
X327997Y-325772D02*
X327497Y-325272D01*
X326498D01*
X325998Y-325772D01*
Y-326272D01*
X326498Y-326772D01*
X327497D01*
X327997Y-327272D01*
Y-327771D01*
X327497Y-328271D01*
X326498D01*
X325998Y-327771D01*
X328997Y-325272D02*
Y-328271D01*
Y-327272D01*
X330996Y-325272D01*
X329497Y-326772D01*
X330996Y-328271D01*
X331996Y-325272D02*
X333995D01*
X332996D01*
Y-328271D01*
X334995Y-327771D02*
X335495Y-328271D01*
X336494D01*
X336994Y-327771D01*
Y-325772D01*
X336494Y-325272D01*
X335495D01*
X334995Y-325772D01*
Y-326272D01*
X335495Y-326772D01*
X336994D01*
X257525Y-339551D02*
X257025Y-339052D01*
X256025D01*
X255525Y-339551D01*
Y-340051D01*
X256025Y-340551D01*
X257025D01*
X257525Y-341051D01*
Y-341551D01*
X257025Y-342051D01*
X256025D01*
X255525Y-341551D01*
X258524Y-339052D02*
Y-342051D01*
Y-341051D01*
X260524Y-339052D01*
X259024Y-340551D01*
X260524Y-342051D01*
X261524Y-339052D02*
X263523D01*
X262523D01*
Y-342051D01*
X264523Y-339551D02*
X265022Y-339052D01*
X266022D01*
X266522Y-339551D01*
Y-340051D01*
X266022Y-340551D01*
X266522Y-341051D01*
Y-341551D01*
X266022Y-342051D01*
X265022D01*
X264523Y-341551D01*
Y-341051D01*
X265022Y-340551D01*
X264523Y-340051D01*
Y-339551D01*
X265022Y-340551D02*
X266022D01*
X326029Y-166323D02*
X325529Y-165823D01*
X324529D01*
X324029Y-166323D01*
Y-166823D01*
X324529Y-167323D01*
X325529D01*
X326029Y-167823D01*
Y-168323D01*
X325529Y-168822D01*
X324529D01*
X324029Y-168323D01*
X327028Y-165823D02*
Y-168822D01*
Y-167823D01*
X329028Y-165823D01*
X327528Y-167323D01*
X329028Y-168822D01*
X330027Y-165823D02*
X332027D01*
X331027D01*
Y-168822D01*
X333026Y-165823D02*
X335026D01*
Y-166323D01*
X333026Y-168323D01*
Y-168822D01*
X110674Y-236008D02*
X110175Y-235508D01*
X109175D01*
X108675Y-236008D01*
Y-236508D01*
X109175Y-237008D01*
X110175D01*
X110674Y-237508D01*
Y-238007D01*
X110175Y-238507D01*
X109175D01*
X108675Y-238007D01*
X111674Y-235508D02*
Y-238507D01*
Y-237508D01*
X113673Y-235508D01*
X112174Y-237008D01*
X113673Y-238507D01*
X114673Y-235508D02*
X116672D01*
X115673D01*
Y-238507D01*
X119671Y-235508D02*
X118672Y-236008D01*
X117672Y-237008D01*
Y-238007D01*
X118172Y-238507D01*
X119172D01*
X119671Y-238007D01*
Y-237508D01*
X119172Y-237008D01*
X117672D01*
X139415Y-341520D02*
X138915Y-341020D01*
X137915D01*
X137415Y-341520D01*
Y-342020D01*
X137915Y-342520D01*
X138915D01*
X139415Y-343020D01*
Y-343519D01*
X138915Y-344019D01*
X137915D01*
X137415Y-343519D01*
X140414Y-341020D02*
Y-344019D01*
Y-343020D01*
X142414Y-341020D01*
X140914Y-342520D01*
X142414Y-344019D01*
X143413Y-341020D02*
X145413D01*
X144413D01*
Y-344019D01*
X148412Y-341020D02*
X146412D01*
Y-342520D01*
X147412Y-342020D01*
X147912D01*
X148412Y-342520D01*
Y-343519D01*
X147912Y-344019D01*
X146912D01*
X146412Y-343519D01*
X301619Y-339551D02*
X301119Y-339052D01*
X300120D01*
X299620Y-339551D01*
Y-340051D01*
X300120Y-340551D01*
X301119D01*
X301619Y-341051D01*
Y-341551D01*
X301119Y-342051D01*
X300120D01*
X299620Y-341551D01*
X302619Y-339052D02*
Y-342051D01*
Y-341051D01*
X304618Y-339052D01*
X303119Y-340551D01*
X304618Y-342051D01*
X305618Y-339052D02*
X307617D01*
X306618D01*
Y-342051D01*
X310117D02*
Y-339052D01*
X308617Y-340551D01*
X310616D01*
X286265Y-339551D02*
X285765Y-339052D01*
X284765D01*
X284266Y-339551D01*
Y-340051D01*
X284765Y-340551D01*
X285765D01*
X286265Y-341051D01*
Y-341551D01*
X285765Y-342051D01*
X284765D01*
X284266Y-341551D01*
X287265Y-339052D02*
Y-342051D01*
Y-341051D01*
X289264Y-339052D01*
X287764Y-340551D01*
X289264Y-342051D01*
X290264Y-339052D02*
X292263D01*
X291263D01*
Y-342051D01*
X293263Y-339551D02*
X293762Y-339052D01*
X294762D01*
X295262Y-339551D01*
Y-340051D01*
X294762Y-340551D01*
X294262D01*
X294762D01*
X295262Y-341051D01*
Y-341551D01*
X294762Y-342051D01*
X293762D01*
X293263Y-341551D01*
X111462Y-156481D02*
X110962Y-155981D01*
X109962D01*
X109462Y-156481D01*
Y-156981D01*
X109962Y-157480D01*
X110962D01*
X111462Y-157980D01*
Y-158480D01*
X110962Y-158980D01*
X109962D01*
X109462Y-158480D01*
X112461Y-155981D02*
Y-158980D01*
Y-157980D01*
X114461Y-155981D01*
X112961Y-157480D01*
X114461Y-158980D01*
X115461Y-155981D02*
X117460D01*
X116460D01*
Y-158980D01*
X120459D02*
X118459D01*
X120459Y-156981D01*
Y-156481D01*
X119959Y-155981D01*
X118959D01*
X118459Y-156481D01*
X271410Y-339551D02*
X270911Y-339052D01*
X269911D01*
X269411Y-339551D01*
Y-340051D01*
X269911Y-340551D01*
X270911D01*
X271410Y-341051D01*
Y-341551D01*
X270911Y-342051D01*
X269911D01*
X269411Y-341551D01*
X272410Y-339052D02*
Y-342051D01*
Y-341051D01*
X274410Y-339052D01*
X272910Y-340551D01*
X274410Y-342051D01*
X275409Y-339052D02*
X277409D01*
X276409D01*
Y-342051D01*
X278408D02*
X279408D01*
X278908D01*
Y-339052D01*
X278408Y-339551D01*
X131421Y-122078D02*
X128422D01*
Y-120579D01*
X128922Y-120079D01*
X129921D01*
X130421Y-120579D01*
Y-122078D01*
X131421Y-119079D02*
Y-118079D01*
Y-118579D01*
X128422D01*
X128922Y-119079D01*
X375868Y-137326D02*
Y-134327D01*
X377368D01*
X377868Y-134827D01*
Y-135827D01*
X377368Y-136327D01*
X375868D01*
X376868D02*
X377868Y-137326D01*
X380367D02*
Y-134327D01*
X378867Y-135827D01*
X380867D01*
X381866Y-134327D02*
X383866D01*
Y-134827D01*
X381866Y-136826D01*
Y-137326D01*
X634283Y-111174D02*
X633283D01*
X633783D01*
Y-113673D01*
X633283Y-114173D01*
X632783D01*
X632283Y-113673D01*
X635283Y-111674D02*
X635782Y-111174D01*
X636782D01*
X637282Y-111674D01*
Y-112174D01*
X636782Y-112674D01*
X636282D01*
X636782D01*
X637282Y-113174D01*
Y-113673D01*
X636782Y-114173D01*
X635782D01*
X635283Y-113673D01*
X638281Y-111674D02*
X638781Y-111174D01*
X639781D01*
X640281Y-111674D01*
Y-112174D01*
X639781Y-112674D01*
X640281Y-113174D01*
Y-113673D01*
X639781Y-114173D01*
X638781D01*
X638281Y-113673D01*
Y-113174D01*
X638781Y-112674D01*
X638281Y-112174D01*
Y-111674D01*
X638781Y-112674D02*
X639781D01*
X375868Y-114492D02*
Y-111493D01*
X377368D01*
X377868Y-111993D01*
Y-112992D01*
X377368Y-113492D01*
X375868D01*
X376868D02*
X377868Y-114492D01*
X380367D02*
Y-111493D01*
X378867Y-112992D01*
X380867D01*
X383866Y-111493D02*
X382866Y-111993D01*
X381866Y-112992D01*
Y-113992D01*
X382366Y-114492D01*
X383366D01*
X383866Y-113992D01*
Y-113492D01*
X383366Y-112992D01*
X381866D01*
X376262Y-126303D02*
Y-123304D01*
X377762D01*
X378261Y-123803D01*
Y-124803D01*
X377762Y-125303D01*
X376262D01*
X377262D02*
X378261Y-126303D01*
X380761D02*
Y-123304D01*
X379261Y-124803D01*
X381260D01*
X384259Y-123304D02*
X382260D01*
Y-124803D01*
X383260Y-124303D01*
X383759D01*
X384259Y-124803D01*
Y-125803D01*
X383759Y-126303D01*
X382760D01*
X382260Y-125803D01*
X607936Y-172910D02*
Y-175909D01*
X606436D01*
X605936Y-175409D01*
Y-174409D01*
X606436Y-173910D01*
X607936D01*
X606936D02*
X605936Y-172910D01*
X603437D02*
Y-175909D01*
X604937Y-174409D01*
X602937D01*
X600438Y-172910D02*
Y-175909D01*
X601938Y-174409D01*
X599938D01*
X621448Y-152044D02*
Y-155043D01*
X622948D01*
X623447Y-154543D01*
Y-152544D01*
X622948Y-152044D01*
X621448D01*
X624447Y-155043D02*
X625447D01*
X624947D01*
Y-152044D01*
X624447Y-152544D01*
X626946Y-154543D02*
X627446Y-155043D01*
X628446D01*
X628946Y-154543D01*
Y-152544D01*
X628446Y-152044D01*
X627446D01*
X626946Y-152544D01*
Y-153043D01*
X627446Y-153543D01*
X628946D01*
X613310Y-130897D02*
X610312D01*
Y-132396D01*
X610811Y-132896D01*
X612811D01*
X613310Y-132396D01*
Y-130897D01*
X610312Y-133896D02*
Y-134896D01*
Y-134396D01*
X613310D01*
X612811Y-133896D01*
X610312Y-138394D02*
Y-136395D01*
X612311Y-138394D01*
X612811D01*
X613310Y-137895D01*
Y-136895D01*
X612811Y-136395D01*
X376326Y-313049D02*
Y-314049D01*
Y-313549D01*
X378825D01*
X379325Y-314049D01*
Y-314549D01*
X378825Y-315049D01*
X376826Y-312050D02*
X376326Y-311550D01*
Y-310550D01*
X376826Y-310050D01*
X377326D01*
X377826Y-310550D01*
Y-311050D01*
Y-310550D01*
X378326Y-310050D01*
X378825D01*
X379325Y-310550D01*
Y-311550D01*
X378825Y-312050D01*
X376326Y-309051D02*
Y-307051D01*
X376826D01*
X378825Y-309051D01*
X379325D01*
X336452Y-179462D02*
X335453D01*
X335953D01*
Y-181961D01*
X335453Y-182460D01*
X334953D01*
X334453Y-181961D01*
X337452Y-179961D02*
X337952Y-179462D01*
X338952D01*
X339451Y-179961D01*
Y-180461D01*
X338952Y-180961D01*
X338452D01*
X338952D01*
X339451Y-181461D01*
Y-181961D01*
X338952Y-182460D01*
X337952D01*
X337452Y-181961D01*
X342450Y-179462D02*
X341451Y-179961D01*
X340451Y-180961D01*
Y-181961D01*
X340951Y-182460D01*
X341951D01*
X342450Y-181961D01*
Y-181461D01*
X341951Y-180961D01*
X340451D01*
X485493Y-156025D02*
Y-155025D01*
Y-155525D01*
X482994D01*
X482494Y-155025D01*
Y-154525D01*
X482994Y-154025D01*
X484993Y-157024D02*
X485493Y-157524D01*
Y-158524D01*
X484993Y-159024D01*
X484493D01*
X483994Y-158524D01*
Y-158024D01*
Y-158524D01*
X483494Y-159024D01*
X482994D01*
X482494Y-158524D01*
Y-157524D01*
X482994Y-157024D01*
X485493Y-162023D02*
Y-160023D01*
X483994D01*
X484493Y-161023D01*
Y-161523D01*
X483994Y-162023D01*
X482994D01*
X482494Y-161523D01*
Y-160523D01*
X482994Y-160023D01*
X525228Y-285358D02*
X526227D01*
X525728D01*
Y-282859D01*
X526227Y-282359D01*
X526727D01*
X527227Y-282859D01*
X524228Y-284858D02*
X523728Y-285358D01*
X522728D01*
X522229Y-284858D01*
Y-284358D01*
X522728Y-283858D01*
X523228D01*
X522728D01*
X522229Y-283358D01*
Y-282859D01*
X522728Y-282359D01*
X523728D01*
X524228Y-282859D01*
X519730Y-282359D02*
Y-285358D01*
X521229Y-283858D01*
X519230D01*
X303537Y-264344D02*
X304537D01*
X304037D01*
Y-261844D01*
X304537Y-261345D01*
X305036D01*
X305536Y-261844D01*
X302537Y-263844D02*
X302037Y-264344D01*
X301038D01*
X300538Y-263844D01*
Y-263344D01*
X301038Y-262844D01*
X301537D01*
X301038D01*
X300538Y-262344D01*
Y-261844D01*
X301038Y-261345D01*
X302037D01*
X302537Y-261844D01*
X299538Y-261345D02*
X298538D01*
X299038D01*
Y-264344D01*
X299538Y-263844D01*
X633290Y-3619D02*
X632290D01*
X632790D01*
Y-6118D01*
X632290Y-6618D01*
X631790D01*
X631291Y-6118D01*
X634290Y-6618D02*
X635289D01*
X634790D01*
Y-3619D01*
X634290Y-4118D01*
X636789D02*
X637289Y-3619D01*
X638288D01*
X638788Y-4118D01*
Y-4618D01*
X638288Y-5118D01*
X637788D01*
X638288D01*
X638788Y-5618D01*
Y-6118D01*
X638288Y-6618D01*
X637289D01*
X636789Y-6118D01*
X89452Y-87986D02*
Y-86986D01*
Y-87486D01*
X86953D01*
X86453Y-86986D01*
Y-86486D01*
X86953Y-85986D01*
X89452Y-90985D02*
X88952Y-89985D01*
X87952Y-88986D01*
X86953D01*
X86453Y-89485D01*
Y-90485D01*
X86953Y-90985D01*
X87453D01*
X87952Y-90485D01*
Y-88986D01*
X647319Y-74742D02*
X650318D01*
Y-76241D01*
X649819Y-76741D01*
X648819D01*
X648319Y-76241D01*
Y-74742D01*
Y-75741D02*
X647319Y-76741D01*
Y-79240D02*
X650318D01*
X648819Y-77741D01*
Y-79740D01*
X649819Y-80739D02*
X650318Y-81239D01*
Y-82239D01*
X649819Y-82739D01*
X649319D01*
X648819Y-82239D01*
Y-81739D01*
Y-82239D01*
X648319Y-82739D01*
X647819D01*
X647319Y-82239D01*
Y-81239D01*
X647819Y-80739D01*
X673560Y-38901D02*
Y-35902D01*
X675060D01*
X675560Y-36402D01*
Y-37402D01*
X675060Y-37901D01*
X673560D01*
X674560D02*
X675560Y-38901D01*
X678059D02*
Y-35902D01*
X676559Y-37402D01*
X678559D01*
X681558Y-38901D02*
X679558D01*
X681558Y-36902D01*
Y-36402D01*
X681058Y-35902D01*
X680058D01*
X679558Y-36402D01*
X38855Y-18513D02*
X41854D01*
Y-17013D01*
X41354Y-16513D01*
X39355D01*
X38855Y-17013D01*
Y-18513D01*
X41854Y-15514D02*
Y-14514D01*
Y-15014D01*
X38855D01*
X39355Y-15514D01*
Y-13014D02*
X38855Y-12515D01*
Y-11515D01*
X39355Y-11015D01*
X41354D01*
X41854Y-11515D01*
Y-12515D01*
X41354Y-13014D01*
X39355D01*
X30981Y-18247D02*
X33980D01*
Y-16748D01*
X33480Y-16248D01*
X31481D01*
X30981Y-16748D01*
Y-18247D01*
X33480Y-15248D02*
X33980Y-14748D01*
Y-13749D01*
X33480Y-13249D01*
X31481D01*
X30981Y-13749D01*
Y-14748D01*
X31481Y-15248D01*
X31980D01*
X32480Y-14748D01*
Y-13249D01*
X25075Y-18247D02*
X28074D01*
Y-16748D01*
X27575Y-16248D01*
X25575D01*
X25075Y-16748D01*
Y-18247D01*
X25575Y-15248D02*
X25075Y-14748D01*
Y-13749D01*
X25575Y-13249D01*
X26075D01*
X26575Y-13749D01*
Y-14248D01*
Y-13749D01*
X27075Y-13249D01*
X27575D01*
X28074Y-13749D01*
Y-14748D01*
X27575Y-15248D01*
X78552Y-312523D02*
Y-310024D01*
X78052Y-309524D01*
X77052D01*
X76553Y-310024D01*
Y-312523D01*
X75553Y-309524D02*
X74553D01*
X75053D01*
Y-312523D01*
X75553Y-312023D01*
X71054Y-312523D02*
X72054Y-312023D01*
X73054Y-311024D01*
Y-310024D01*
X72554Y-309524D01*
X71554D01*
X71054Y-310024D01*
Y-310524D01*
X71554Y-311024D01*
X73054D01*
X79536Y-206224D02*
Y-203725D01*
X79036Y-203225D01*
X78037D01*
X77537Y-203725D01*
Y-206224D01*
X76537Y-203225D02*
X75538D01*
X76037D01*
Y-206224D01*
X76537Y-205724D01*
X72039Y-203225D02*
X74038D01*
X72039Y-205224D01*
Y-205724D01*
X72538Y-206224D01*
X73538D01*
X74038Y-205724D01*
X79332Y-258389D02*
Y-255890D01*
X78832Y-255390D01*
X77832D01*
X77332Y-255890D01*
Y-258389D01*
X76333Y-255390D02*
X75333D01*
X75833D01*
Y-258389D01*
X76333Y-257889D01*
X73833Y-255390D02*
X72834D01*
X73334D01*
Y-258389D01*
X73833Y-257889D01*
X77302Y-153074D02*
Y-150575D01*
X76802Y-150075D01*
X75803D01*
X75303Y-150575D01*
Y-153074D01*
X74303Y-152575D02*
X73803Y-153074D01*
X72804D01*
X72304Y-152575D01*
Y-152075D01*
X72804Y-151575D01*
X72304Y-151075D01*
Y-150575D01*
X72804Y-150075D01*
X73803D01*
X74303Y-150575D01*
Y-151075D01*
X73803Y-151575D01*
X74303Y-152075D01*
Y-152575D01*
X73803Y-151575D02*
X72804D01*
X91005Y-109721D02*
Y-112220D01*
X91505Y-112720D01*
X92504D01*
X93004Y-112220D01*
Y-109721D01*
X96003D02*
X95003Y-110221D01*
X94004Y-111221D01*
Y-112220D01*
X94504Y-112720D01*
X95503D01*
X96003Y-112220D01*
Y-111720D01*
X95503Y-111221D01*
X94004D01*
X65399Y-137326D02*
Y-134327D01*
X66898D01*
X67398Y-134827D01*
Y-135827D01*
X66898Y-136327D01*
X65399D01*
X66398D02*
X67398Y-137326D01*
X69897D02*
Y-134327D01*
X68398Y-135827D01*
X70397D01*
X71397Y-137326D02*
X72396D01*
X71897D01*
Y-134327D01*
X71397Y-134827D01*
X83920Y-114642D02*
Y-117641D01*
X82420D01*
X81921Y-117141D01*
Y-116142D01*
X82420Y-115642D01*
X83920D01*
X82920D02*
X81921Y-114642D01*
X79421D02*
Y-117641D01*
X80921Y-116142D01*
X78922D01*
X77922Y-117141D02*
X77422Y-117641D01*
X76422D01*
X75923Y-117141D01*
Y-115142D01*
X76422Y-114642D01*
X77422D01*
X77922Y-115142D01*
Y-117141D01*
X48744Y-29589D02*
X45745D01*
Y-28090D01*
X46244Y-27590D01*
X47244D01*
X47744Y-28090D01*
Y-29589D01*
Y-28590D02*
X48744Y-27590D01*
X46244Y-26590D02*
X45745Y-26090D01*
Y-25091D01*
X46244Y-24591D01*
X46744D01*
X47244Y-25091D01*
Y-25591D01*
Y-25091D01*
X47744Y-24591D01*
X48244D01*
X48744Y-25091D01*
Y-26090D01*
X48244Y-26590D01*
Y-23591D02*
X48744Y-23091D01*
Y-22092D01*
X48244Y-21592D01*
X46244D01*
X45745Y-22092D01*
Y-23091D01*
X46244Y-23591D01*
X46744D01*
X47244Y-23091D01*
Y-21592D01*
X41854Y-29589D02*
X38855D01*
Y-28090D01*
X39355Y-27590D01*
X40354D01*
X40854Y-28090D01*
Y-29589D01*
Y-28590D02*
X41854Y-27590D01*
X39355Y-26590D02*
X38855Y-26090D01*
Y-25091D01*
X39355Y-24591D01*
X39854D01*
X40354Y-25091D01*
Y-25591D01*
Y-25091D01*
X40854Y-24591D01*
X41354D01*
X41854Y-25091D01*
Y-26090D01*
X41354Y-26590D01*
X39355Y-23591D02*
X38855Y-23091D01*
Y-22092D01*
X39355Y-21592D01*
X39854D01*
X40354Y-22092D01*
X40854Y-21592D01*
X41354D01*
X41854Y-22092D01*
Y-23091D01*
X41354Y-23591D01*
X40854D01*
X40354Y-23091D01*
X39854Y-23591D01*
X39355D01*
X40354Y-23091D02*
Y-22092D01*
X33980Y-29589D02*
X30981D01*
Y-28090D01*
X31481Y-27590D01*
X32480D01*
X32980Y-28090D01*
Y-29589D01*
Y-28590D02*
X33980Y-27590D01*
X31481Y-26590D02*
X30981Y-26090D01*
Y-25091D01*
X31481Y-24591D01*
X31980D01*
X32480Y-25091D01*
Y-25591D01*
Y-25091D01*
X32980Y-24591D01*
X33480D01*
X33980Y-25091D01*
Y-26090D01*
X33480Y-26590D01*
X30981Y-21592D02*
X31481Y-22591D01*
X32480Y-23591D01*
X33480D01*
X33980Y-23091D01*
Y-22092D01*
X33480Y-21592D01*
X32980D01*
X32480Y-22092D01*
Y-23591D01*
X28074Y-29589D02*
X25075D01*
Y-28090D01*
X25575Y-27590D01*
X26575D01*
X27075Y-28090D01*
Y-29589D01*
Y-28590D02*
X28074Y-27590D01*
X25575Y-26590D02*
X25075Y-26090D01*
Y-25091D01*
X25575Y-24591D01*
X26075D01*
X26575Y-25091D01*
Y-25591D01*
Y-25091D01*
X27075Y-24591D01*
X27575D01*
X28074Y-25091D01*
Y-26090D01*
X27575Y-26590D01*
X25075Y-21592D02*
Y-23591D01*
X26575D01*
X26075Y-22591D01*
Y-22092D01*
X26575Y-21592D01*
X27575D01*
X28074Y-22092D01*
Y-23091D01*
X27575Y-23591D01*
X52891Y-312523D02*
Y-309524D01*
X54391D01*
X54890Y-310024D01*
Y-311024D01*
X54391Y-311524D01*
X52891D01*
X53891D02*
X54890Y-312523D01*
X55890Y-310024D02*
X56390Y-309524D01*
X57390D01*
X57889Y-310024D01*
Y-310524D01*
X57390Y-311024D01*
X56890D01*
X57390D01*
X57889Y-311524D01*
Y-312023D01*
X57390Y-312523D01*
X56390D01*
X55890Y-312023D01*
X60389Y-312523D02*
Y-309524D01*
X58889Y-311024D01*
X60888D01*
X54072Y-206224D02*
Y-203225D01*
X55572D01*
X56072Y-203725D01*
Y-204724D01*
X55572Y-205224D01*
X54072D01*
X55072D02*
X56072Y-206224D01*
X57071Y-203725D02*
X57571Y-203225D01*
X58571D01*
X59071Y-203725D01*
Y-204225D01*
X58571Y-204724D01*
X58071D01*
X58571D01*
X59071Y-205224D01*
Y-205724D01*
X58571Y-206224D01*
X57571D01*
X57071Y-205724D01*
X60070Y-203725D02*
X60570Y-203225D01*
X61570D01*
X62070Y-203725D01*
Y-204225D01*
X61570Y-204724D01*
X61070D01*
X61570D01*
X62070Y-205224D01*
Y-205724D01*
X61570Y-206224D01*
X60570D01*
X60070Y-205724D01*
X76303Y-348487D02*
X73304D01*
Y-346987D01*
X73804Y-346487D01*
X74803D01*
X75303Y-346987D01*
Y-348487D01*
Y-347487D02*
X76303Y-346487D01*
X73804Y-345488D02*
X73304Y-344988D01*
Y-343988D01*
X73804Y-343489D01*
X74303D01*
X74803Y-343988D01*
Y-344488D01*
Y-343988D01*
X75303Y-343489D01*
X75803D01*
X76303Y-343988D01*
Y-344988D01*
X75803Y-345488D01*
X76303Y-340490D02*
Y-342489D01*
X74303Y-340490D01*
X73804D01*
X73304Y-340989D01*
Y-341989D01*
X73804Y-342489D01*
X84177Y-347987D02*
X81178D01*
Y-346487D01*
X81678Y-345988D01*
X82677D01*
X83177Y-346487D01*
Y-347987D01*
Y-346987D02*
X84177Y-345988D01*
X81678Y-344988D02*
X81178Y-344488D01*
Y-343489D01*
X81678Y-342989D01*
X82177D01*
X82677Y-343489D01*
Y-343988D01*
Y-343489D01*
X83177Y-342989D01*
X83677D01*
X84177Y-343489D01*
Y-344488D01*
X83677Y-344988D01*
X84177Y-341989D02*
Y-340989D01*
Y-341489D01*
X81178D01*
X81678Y-341989D01*
X518306Y2086D02*
X515307D01*
Y3586D01*
X515806Y4086D01*
X516806D01*
X517306Y3586D01*
Y2086D01*
X515806Y5085D02*
X515307Y5585D01*
Y6585D01*
X515806Y7085D01*
X516306D01*
X516806Y6585D01*
Y6085D01*
Y6585D01*
X517306Y7085D01*
X517806D01*
X518306Y6585D01*
Y5585D01*
X517806Y5085D01*
X38870Y-304603D02*
X37871D01*
X38370D01*
Y-307102D01*
X37871Y-307602D01*
X37371D01*
X36871Y-307102D01*
X41369Y-307602D02*
Y-304603D01*
X39870Y-306102D01*
X41869D01*
X37886Y-197319D02*
X36886D01*
X37386D01*
Y-199819D01*
X36886Y-200318D01*
X36386D01*
X35887Y-199819D01*
X40885Y-200318D02*
X38886D01*
X40885Y-198319D01*
Y-197819D01*
X40385Y-197319D01*
X39386D01*
X38886Y-197819D01*
X37886Y-249485D02*
X36886D01*
X37386D01*
Y-251984D01*
X36886Y-252484D01*
X36386D01*
X35887Y-251984D01*
X38886Y-249985D02*
X39386Y-249485D01*
X40385D01*
X40885Y-249985D01*
Y-250484D01*
X40385Y-250984D01*
X39885D01*
X40385D01*
X40885Y-251484D01*
Y-251984D01*
X40385Y-252484D01*
X39386D01*
X38886Y-251984D01*
X38386Y-145154D02*
X37386D01*
X37886D01*
Y-147653D01*
X37386Y-148153D01*
X36886D01*
X36386Y-147653D01*
X39386Y-148153D02*
X40385D01*
X39885D01*
Y-145154D01*
X39386Y-145654D01*
X-13310Y-348237D02*
X-10311D01*
Y-346737D01*
X-10811Y-346238D01*
X-12811D01*
X-13310Y-346737D01*
Y-348237D01*
X-10311Y-345238D02*
Y-344238D01*
Y-344738D01*
X-13310D01*
X-12811Y-345238D01*
Y-342739D02*
X-13310Y-342239D01*
Y-341239D01*
X-12811Y-340739D01*
X-12311D01*
X-11811Y-341239D01*
X-11311Y-340739D01*
X-10811D01*
X-10311Y-341239D01*
Y-342239D01*
X-10811Y-342739D01*
X-11311D01*
X-11811Y-342239D01*
X-12311Y-342739D01*
X-12811D01*
X-11811Y-342239D02*
Y-341239D01*
X-13310Y-295087D02*
X-10311D01*
Y-293588D01*
X-10811Y-293088D01*
X-12811D01*
X-13310Y-293588D01*
Y-295087D01*
X-10311Y-292088D02*
Y-291089D01*
Y-291588D01*
X-13310D01*
X-12811Y-292088D01*
X-13310Y-289589D02*
Y-287590D01*
X-12811D01*
X-10811Y-289589D01*
X-10311D01*
X-13310Y-241938D02*
X-10311D01*
Y-240438D01*
X-10811Y-239938D01*
X-12811D01*
X-13310Y-240438D01*
Y-241938D01*
X-10311Y-238939D02*
Y-237939D01*
Y-238439D01*
X-13310D01*
X-12811Y-238939D01*
X-13310Y-234440D02*
X-12811Y-235440D01*
X-11811Y-236439D01*
X-10811D01*
X-10311Y-235940D01*
Y-234940D01*
X-10811Y-234440D01*
X-11311D01*
X-11811Y-234940D01*
Y-236439D01*
X-13310Y-188788D02*
X-10311D01*
Y-187289D01*
X-10811Y-186789D01*
X-12811D01*
X-13310Y-187289D01*
Y-188788D01*
X-10311Y-185789D02*
Y-184789D01*
Y-185289D01*
X-13310D01*
X-12811Y-185789D01*
X-13310Y-181291D02*
Y-183290D01*
X-11811D01*
X-12311Y-182290D01*
Y-181790D01*
X-11811Y-181291D01*
X-10811D01*
X-10311Y-181790D01*
Y-182790D01*
X-10811Y-183290D01*
X67898Y-126999D02*
X67398Y-127499D01*
Y-128499D01*
X67898Y-128999D01*
X69897D01*
X70397Y-128499D01*
Y-127499D01*
X69897Y-126999D01*
X70397Y-124500D02*
X67398D01*
X68898Y-126000D01*
Y-124000D01*
X67898Y-123001D02*
X67398Y-122501D01*
Y-121501D01*
X67898Y-121001D01*
X69897D01*
X70397Y-121501D01*
Y-122501D01*
X69897Y-123001D01*
X67898D01*
X62977Y-126999D02*
X62477Y-127499D01*
Y-128499D01*
X62977Y-128999D01*
X64976D01*
X65476Y-128499D01*
Y-127499D01*
X64976Y-126999D01*
X62977Y-126000D02*
X62477Y-125500D01*
Y-124500D01*
X62977Y-124000D01*
X63477D01*
X63976Y-124500D01*
Y-125000D01*
Y-124500D01*
X64476Y-124000D01*
X64976D01*
X65476Y-124500D01*
Y-125500D01*
X64976Y-126000D01*
X62977Y-123001D02*
X62477Y-122501D01*
Y-121501D01*
X62977Y-121001D01*
X63477D01*
X63976Y-121501D01*
X64476Y-121001D01*
X64976D01*
X65476Y-121501D01*
Y-122501D01*
X64976Y-123001D01*
X64476D01*
X63976Y-122501D01*
X63477Y-123001D01*
X62977D01*
X63976Y-122501D02*
Y-121501D01*
X505087Y-141914D02*
X504587Y-141414D01*
X503588D01*
X503088Y-141914D01*
Y-143913D01*
X503588Y-144413D01*
X504587D01*
X505087Y-143913D01*
X506087Y-141914D02*
X506587Y-141414D01*
X507586D01*
X508086Y-141914D01*
Y-142414D01*
X507586Y-142913D01*
X507087D01*
X507586D01*
X508086Y-143413D01*
Y-143913D01*
X507586Y-144413D01*
X506587D01*
X506087Y-143913D01*
X509086Y-141914D02*
X509586Y-141414D01*
X510585D01*
X511085Y-141914D01*
Y-142414D01*
X510585Y-142913D01*
X510086D01*
X510585D01*
X511085Y-143413D01*
Y-143913D01*
X510585Y-144413D01*
X509586D01*
X509086Y-143913D01*
X505087Y-137583D02*
X504587Y-137083D01*
X503588D01*
X503088Y-137583D01*
Y-139582D01*
X503588Y-140082D01*
X504587D01*
X505087Y-139582D01*
X506087Y-137583D02*
X506587Y-137083D01*
X507586D01*
X508086Y-137583D01*
Y-138083D01*
X507586Y-138583D01*
X507087D01*
X507586D01*
X508086Y-139083D01*
Y-139582D01*
X507586Y-140082D01*
X506587D01*
X506087Y-139582D01*
X511085Y-140082D02*
X509086D01*
X511085Y-138083D01*
Y-137583D01*
X510585Y-137083D01*
X509586D01*
X509086Y-137583D01*
X445214Y-139689D02*
Y-136689D01*
X446713D01*
X447213Y-137189D01*
Y-138189D01*
X446713Y-138689D01*
X445214D01*
X446214D02*
X447213Y-139689D01*
X448213Y-137189D02*
X448713Y-136689D01*
X449712D01*
X450212Y-137189D01*
Y-137689D01*
X449712Y-138189D01*
X449213D01*
X449712D01*
X450212Y-138689D01*
Y-139189D01*
X449712Y-139689D01*
X448713D01*
X448213Y-139189D01*
X451212Y-136689D02*
X453211D01*
Y-137189D01*
X451212Y-139189D01*
Y-139689D01*
X394957Y-98631D02*
X397456D01*
X397956Y-98131D01*
Y-97131D01*
X397456Y-96631D01*
X394957D01*
X397956Y-95632D02*
Y-94632D01*
Y-95132D01*
X394957D01*
X395457Y-95632D01*
X394957Y-91133D02*
Y-93132D01*
X396457D01*
X395957Y-92133D01*
Y-91633D01*
X396457Y-91133D01*
X397456D01*
X397956Y-91633D01*
Y-92633D01*
X397456Y-93132D01*
X668867Y-10024D02*
X668367Y-9524D01*
X667367D01*
X666867Y-10024D01*
Y-12023D01*
X667367Y-12523D01*
X668367D01*
X668867Y-12023D01*
X669867Y-10024D02*
X670366Y-9524D01*
X671366D01*
X671866Y-10024D01*
Y-10524D01*
X671366Y-11024D01*
X670866D01*
X671366D01*
X671866Y-11523D01*
Y-12023D01*
X671366Y-12523D01*
X670366D01*
X669867Y-12023D01*
X672865Y-9524D02*
X674865D01*
Y-10024D01*
X672865Y-12023D01*
Y-12523D01*
X598394Y-12632D02*
X597894Y-12132D01*
X596895D01*
X596395Y-12632D01*
Y-14631D01*
X596895Y-15131D01*
X597894D01*
X598394Y-14631D01*
X599394Y-12632D02*
X599894Y-12132D01*
X600894D01*
X601393Y-12632D01*
Y-13132D01*
X600894Y-13632D01*
X600394D01*
X600894D01*
X601393Y-14131D01*
Y-14631D01*
X600894Y-15131D01*
X599894D01*
X599394Y-14631D01*
X604392Y-12132D02*
X603393Y-12632D01*
X602393Y-13632D01*
Y-14631D01*
X602893Y-15131D01*
X603893D01*
X604392Y-14631D01*
Y-14131D01*
X603893Y-13632D01*
X602393D01*
X677135Y-17898D02*
X676635Y-17398D01*
X675635D01*
X675135Y-17898D01*
Y-19897D01*
X675635Y-20397D01*
X676635D01*
X677135Y-19897D01*
X678134Y-17898D02*
X678634Y-17398D01*
X679634D01*
X680133Y-17898D01*
Y-18398D01*
X679634Y-18898D01*
X679134D01*
X679634D01*
X680133Y-19398D01*
Y-19897D01*
X679634Y-20397D01*
X678634D01*
X678134Y-19897D01*
X683133Y-17398D02*
X681133D01*
Y-18898D01*
X682133Y-18398D01*
X682633D01*
X683133Y-18898D01*
Y-19897D01*
X682633Y-20397D01*
X681633D01*
X681133Y-19897D01*
X598394Y-20506D02*
X597894Y-20006D01*
X596895D01*
X596395Y-20506D01*
Y-22505D01*
X596895Y-23005D01*
X597894D01*
X598394Y-22505D01*
X599394Y-20506D02*
X599894Y-20006D01*
X600894D01*
X601393Y-20506D01*
Y-21006D01*
X600894Y-21506D01*
X600394D01*
X600894D01*
X601393Y-22005D01*
Y-22505D01*
X600894Y-23005D01*
X599894D01*
X599394Y-22505D01*
X603893Y-23005D02*
Y-20006D01*
X602393Y-21506D01*
X604392D01*
X35690Y-297319D02*
Y-300318D01*
X37189D01*
X37689Y-299819D01*
Y-297819D01*
X37189Y-297319D01*
X35690D01*
X40688Y-300318D02*
X38689D01*
X40688Y-298319D01*
Y-297819D01*
X40188Y-297319D01*
X39189D01*
X38689Y-297819D01*
X37371Y-189052D02*
Y-192051D01*
X38870D01*
X39370Y-191551D01*
Y-189551D01*
X38870Y-189052D01*
X37371D01*
X40370Y-192051D02*
X41369D01*
X40870D01*
Y-189052D01*
X40370Y-189551D01*
X174348Y-110948D02*
Y-107949D01*
X175847D01*
X176347Y-108449D01*
Y-109449D01*
X175847Y-109949D01*
X174348D01*
X175347D02*
X176347Y-110948D01*
X179346D02*
X177347D01*
X179346Y-108949D01*
Y-108449D01*
X178846Y-107949D01*
X177847D01*
X177347Y-108449D01*
X180346Y-107949D02*
X182345D01*
Y-108449D01*
X180346Y-110449D01*
Y-110948D01*
X159068Y-111062D02*
Y-108063D01*
X160568D01*
X161068Y-108563D01*
Y-109562D01*
X160568Y-110062D01*
X159068D01*
X160068D02*
X161068Y-111062D01*
X164067D02*
X162067D01*
X164067Y-109063D01*
Y-108563D01*
X163567Y-108063D01*
X162567D01*
X162067Y-108563D01*
X167066Y-108063D02*
X166066Y-108563D01*
X165066Y-109562D01*
Y-110562D01*
X165566Y-111062D01*
X166566D01*
X167066Y-110562D01*
Y-110062D01*
X166566Y-109562D01*
X165066D01*
X309637Y-131571D02*
Y-134071D01*
X310137Y-134570D01*
X311137D01*
X311636Y-134071D01*
Y-131571D01*
X312636Y-134570D02*
X313636D01*
X313136D01*
Y-131571D01*
X312636Y-132071D01*
X315135D02*
X315635Y-131571D01*
X316635D01*
X317135Y-132071D01*
Y-134071D01*
X316635Y-134570D01*
X315635D01*
X315135Y-134071D01*
Y-132071D01*
X84177Y-187804D02*
X81178D01*
Y-186304D01*
X81678Y-185804D01*
X82677D01*
X83177Y-186304D01*
Y-187804D01*
Y-186804D02*
X84177Y-185804D01*
Y-184805D02*
Y-183805D01*
Y-184305D01*
X81178D01*
X81678Y-184805D01*
X84177Y-180806D02*
X81178D01*
X82677Y-182306D01*
Y-180306D01*
X517792Y-140363D02*
X520291D01*
X520791Y-139863D01*
Y-138863D01*
X520291Y-138364D01*
X517792D01*
X520791Y-137364D02*
Y-136364D01*
Y-136864D01*
X517792D01*
X518292Y-137364D01*
X520791Y-133365D02*
X517792D01*
X519291Y-134865D01*
Y-132865D01*
X478928Y-133146D02*
Y-135645D01*
X479428Y-136145D01*
X480428D01*
X480928Y-135645D01*
Y-133146D01*
X481927Y-136145D02*
X482927D01*
X482427D01*
Y-133146D01*
X481927Y-133646D01*
X484427D02*
X484927Y-133146D01*
X485926D01*
X486426Y-133646D01*
Y-134146D01*
X485926Y-134646D01*
X485426D01*
X485926D01*
X486426Y-135145D01*
Y-135645D01*
X485926Y-136145D01*
X484927D01*
X484427Y-135645D01*
X219154Y-107556D02*
Y-110055D01*
X219654Y-110555D01*
X220654D01*
X221154Y-110055D01*
Y-107556D01*
X223653Y-110555D02*
Y-107556D01*
X222153Y-109055D01*
X224153D01*
X295532Y-107949D02*
Y-110449D01*
X296032Y-110948D01*
X297032D01*
X297532Y-110449D01*
Y-107949D01*
X298531Y-108449D02*
X299031Y-107949D01*
X300031D01*
X300531Y-108449D01*
Y-108949D01*
X300031Y-109449D01*
X299531D01*
X300031D01*
X300531Y-109949D01*
Y-110449D01*
X300031Y-110948D01*
X299031D01*
X298531Y-110449D01*
X53088Y-154059D02*
Y-151059D01*
X54587D01*
X55087Y-151559D01*
Y-152559D01*
X54587Y-153059D01*
X53088D01*
X54088D02*
X55087Y-154059D01*
X58086D02*
X56087D01*
X58086Y-152059D01*
Y-151559D01*
X57586Y-151059D01*
X56587D01*
X56087Y-151559D01*
X61085Y-151059D02*
X59086D01*
Y-152559D01*
X60086Y-152059D01*
X60585D01*
X61085Y-152559D01*
Y-153559D01*
X60585Y-154059D01*
X59586D01*
X59086Y-153559D01*
X77287Y-294103D02*
X74288D01*
Y-292604D01*
X74788Y-292104D01*
X75787D01*
X76287Y-292604D01*
Y-294103D01*
Y-293103D02*
X77287Y-292104D01*
Y-291104D02*
Y-290104D01*
Y-290604D01*
X74288D01*
X74788Y-291104D01*
X74288Y-288605D02*
Y-286606D01*
X74788D01*
X76787Y-288605D01*
X77287D01*
X692012Y-41716D02*
X695011D01*
Y-43216D01*
X694511Y-43716D01*
X693511D01*
X693012Y-43216D01*
Y-41716D01*
Y-42716D02*
X692012Y-43716D01*
Y-44715D02*
Y-45715D01*
Y-45215D01*
X695011D01*
X694511Y-44715D01*
Y-47214D02*
X695011Y-47714D01*
Y-48714D01*
X694511Y-49214D01*
X694011D01*
X693511Y-48714D01*
Y-48214D01*
Y-48714D01*
X693012Y-49214D01*
X692512D01*
X692012Y-48714D01*
Y-47714D01*
X692512Y-47214D01*
X201303Y-130569D02*
X198304D01*
Y-129070D01*
X198803Y-128570D01*
X199803D01*
X200303Y-129070D01*
Y-130569D01*
Y-129570D02*
X201303Y-128570D01*
Y-127570D02*
Y-126570D01*
Y-127070D01*
X198304D01*
X198803Y-127570D01*
X201303Y-123072D02*
Y-125071D01*
X199303Y-123072D01*
X198803D01*
X198304Y-123572D01*
Y-124571D01*
X198803Y-125071D01*
X263286Y-134964D02*
Y-131965D01*
X264786D01*
X265286Y-132465D01*
Y-133465D01*
X264786Y-133964D01*
X263286D01*
X264286D02*
X265286Y-134964D01*
X266285D02*
X267285D01*
X266785D01*
Y-131965D01*
X266285Y-132465D01*
X268785Y-134964D02*
X269784D01*
X269285D01*
Y-131965D01*
X268785Y-132465D01*
X266330Y-125909D02*
Y-122910D01*
X267829D01*
X268329Y-123410D01*
Y-124409D01*
X267829Y-124909D01*
X266330D01*
X267330D02*
X268329Y-125909D01*
X269329D02*
X270329D01*
X269829D01*
Y-122910D01*
X269329Y-123410D01*
X271828D02*
X272328Y-122910D01*
X273328D01*
X273828Y-123410D01*
Y-125409D01*
X273328Y-125909D01*
X272328D01*
X271828Y-125409D01*
Y-123410D01*
X527544Y-127926D02*
X527044Y-128426D01*
Y-129426D01*
X527544Y-129926D01*
X529543D01*
X530043Y-129426D01*
Y-128426D01*
X529543Y-127926D01*
X527544Y-126927D02*
X527044Y-126427D01*
Y-125427D01*
X527544Y-124927D01*
X528043D01*
X528543Y-125427D01*
Y-125927D01*
Y-125427D01*
X529043Y-124927D01*
X529543D01*
X530043Y-125427D01*
Y-126427D01*
X529543Y-126927D01*
X530043Y-123928D02*
Y-122928D01*
Y-123428D01*
X527044D01*
X527544Y-123928D01*
X515323Y-102150D02*
X514824Y-101650D01*
X513824D01*
X513324Y-102150D01*
Y-104149D01*
X513824Y-104649D01*
X514824D01*
X515323Y-104149D01*
X516323Y-102150D02*
X516823Y-101650D01*
X517823D01*
X518323Y-102150D01*
Y-102650D01*
X517823Y-103150D01*
X517323D01*
X517823D01*
X518323Y-103649D01*
Y-104149D01*
X517823Y-104649D01*
X516823D01*
X516323Y-104149D01*
X519322Y-102150D02*
X519822Y-101650D01*
X520822D01*
X521321Y-102150D01*
Y-104149D01*
X520822Y-104649D01*
X519822D01*
X519322Y-104149D01*
Y-102150D01*
X66914Y-346487D02*
X66414Y-346987D01*
Y-347987D01*
X66914Y-348487D01*
X68913D01*
X69413Y-347987D01*
Y-346987D01*
X68913Y-346487D01*
X69413Y-343489D02*
Y-345488D01*
X67414Y-343489D01*
X66914D01*
X66414Y-343988D01*
Y-344988D01*
X66914Y-345488D01*
X68913Y-342489D02*
X69413Y-341989D01*
Y-340989D01*
X68913Y-340490D01*
X66914D01*
X66414Y-340989D01*
Y-341989D01*
X66914Y-342489D01*
X67414D01*
X67913Y-341989D01*
Y-340490D01*
X67898Y-238220D02*
X67398Y-238720D01*
Y-239719D01*
X67898Y-240219D01*
X69897D01*
X70397Y-239719D01*
Y-238720D01*
X69897Y-238220D01*
X70397Y-235221D02*
Y-237220D01*
X68398Y-235221D01*
X67898D01*
X67398Y-235721D01*
Y-236720D01*
X67898Y-237220D01*
Y-234221D02*
X67398Y-233721D01*
Y-232722D01*
X67898Y-232222D01*
X68398D01*
X68898Y-232722D01*
X69397Y-232222D01*
X69897D01*
X70397Y-232722D01*
Y-233721D01*
X69897Y-234221D01*
X69397D01*
X68898Y-233721D01*
X68398Y-234221D01*
X67898D01*
X68898Y-233721D02*
Y-232722D01*
X67898Y-292354D02*
X67398Y-292853D01*
Y-293853D01*
X67898Y-294353D01*
X69897D01*
X70397Y-293853D01*
Y-292853D01*
X69897Y-292354D01*
X70397Y-289355D02*
Y-291354D01*
X68398Y-289355D01*
X67898D01*
X67398Y-289855D01*
Y-290854D01*
X67898Y-291354D01*
X67398Y-288355D02*
Y-286356D01*
X67898D01*
X69897Y-288355D01*
X70397D01*
X66914Y-186055D02*
X66414Y-186554D01*
Y-187554D01*
X66914Y-188054D01*
X68913D01*
X69413Y-187554D01*
Y-186554D01*
X68913Y-186055D01*
X69413Y-183055D02*
Y-185055D01*
X67414Y-183055D01*
X66914D01*
X66414Y-183555D01*
Y-184555D01*
X66914Y-185055D01*
X66414Y-180056D02*
X66914Y-181056D01*
X67913Y-182056D01*
X68913D01*
X69413Y-181556D01*
Y-180556D01*
X68913Y-180056D01*
X68413D01*
X67913Y-180556D01*
Y-182056D01*
X229497Y-100575D02*
X228997Y-100075D01*
X227997D01*
X227497Y-100575D01*
Y-102575D01*
X227997Y-103074D01*
X228997D01*
X229497Y-102575D01*
X232496Y-103074D02*
X230496D01*
X232496Y-101075D01*
Y-100575D01*
X231996Y-100075D01*
X230996D01*
X230496Y-100575D01*
X234995Y-103074D02*
Y-100075D01*
X233495Y-101575D01*
X235495D01*
X271229Y-101756D02*
X270729Y-101256D01*
X269729D01*
X269230Y-101756D01*
Y-103756D01*
X269729Y-104255D01*
X270729D01*
X271229Y-103756D01*
X274228Y-104255D02*
X272229D01*
X274228Y-102256D01*
Y-101756D01*
X273728Y-101256D01*
X272728D01*
X272229Y-101756D01*
X275228D02*
X275728Y-101256D01*
X276727D01*
X277227Y-101756D01*
Y-102256D01*
X276727Y-102756D01*
X276227D01*
X276727D01*
X277227Y-103256D01*
Y-103756D01*
X276727Y-104255D01*
X275728D01*
X275228Y-103756D01*
X14764Y-146653D02*
X12764D01*
X11765Y-145654D01*
X12764Y-144654D01*
X14764D01*
X13264D01*
Y-146653D01*
X14764Y-143655D02*
X11765D01*
X14764Y-141655D01*
X11765D01*
X14764Y-140656D02*
Y-139656D01*
Y-140156D01*
X11765D01*
X12265Y-140656D01*
X14465Y-253724D02*
X12465D01*
X11466Y-252725D01*
X12465Y-251725D01*
X14465D01*
X12965D01*
Y-253724D01*
X14465Y-250725D02*
X11466D01*
X14465Y-248726D01*
X11466D01*
X11965Y-247726D02*
X11466Y-247227D01*
Y-246227D01*
X11965Y-245727D01*
X12465D01*
X12965Y-246227D01*
Y-246727D01*
Y-246227D01*
X13465Y-245727D01*
X13965D01*
X14465Y-246227D01*
Y-247227D01*
X13965Y-247726D01*
X14465Y-200437D02*
X12465D01*
X11466Y-199437D01*
X12465Y-198438D01*
X14465D01*
X12965D01*
Y-200437D01*
X14465Y-197438D02*
X11466D01*
X14465Y-195439D01*
X11466D01*
X14465Y-192440D02*
Y-194439D01*
X12465Y-192440D01*
X11965D01*
X11466Y-192939D01*
Y-193939D01*
X11965Y-194439D01*
X14071Y-305813D02*
X12071D01*
X11072Y-304813D01*
X12071Y-303813D01*
X14071D01*
X12571D01*
Y-305813D01*
X14071Y-302814D02*
X11072D01*
X14071Y-300814D01*
X11072D01*
X14071Y-298315D02*
X11072D01*
X12571Y-299815D01*
Y-297815D01*
X458131Y-113461D02*
Y-115960D01*
X458631Y-116460D01*
X459630D01*
X460130Y-115960D01*
Y-113461D01*
X461130D02*
X463129D01*
Y-113961D01*
X461130Y-115960D01*
Y-116460D01*
X449031Y-113355D02*
X449531Y-112855D01*
Y-111855D01*
X449031Y-111356D01*
X447032D01*
X446532Y-111855D01*
Y-112855D01*
X447032Y-113355D01*
X446532Y-116354D02*
Y-114355D01*
X448531Y-116354D01*
X449031D01*
X449531Y-115854D01*
Y-114855D01*
X449031Y-114355D01*
X449531Y-119353D02*
Y-117354D01*
X448032D01*
X448531Y-118353D01*
Y-118853D01*
X448032Y-119353D01*
X447032D01*
X446532Y-118853D01*
Y-117853D01*
X447032Y-117354D01*
X85161Y-294103D02*
X82162D01*
Y-292604D01*
X82662Y-292104D01*
X83661D01*
X84161Y-292604D01*
Y-294103D01*
Y-293103D02*
X85161Y-292104D01*
Y-291104D02*
Y-290104D01*
Y-290604D01*
X82162D01*
X82662Y-291104D01*
X82162Y-286606D02*
X82662Y-287605D01*
X83661Y-288605D01*
X84661D01*
X85161Y-288105D01*
Y-287105D01*
X84661Y-286606D01*
X84161D01*
X83661Y-287105D01*
Y-288605D01*
X76303Y-187804D02*
X73304D01*
Y-186304D01*
X73804Y-185804D01*
X74803D01*
X75303Y-186304D01*
Y-187804D01*
Y-186804D02*
X76303Y-185804D01*
Y-184805D02*
Y-183805D01*
Y-184305D01*
X73304D01*
X73804Y-184805D01*
X73304Y-180306D02*
Y-182306D01*
X74803D01*
X74303Y-181306D01*
Y-180806D01*
X74803Y-180306D01*
X75803D01*
X76303Y-180806D01*
Y-181806D01*
X75803Y-182306D01*
X566535Y-227165D02*
X569534D01*
Y-228665D01*
X569035Y-229165D01*
X568035D01*
X567535Y-228665D01*
Y-227165D01*
Y-228165D02*
X566535Y-229165D01*
X569534Y-232164D02*
Y-230164D01*
X568035D01*
X568535Y-231164D01*
Y-231664D01*
X568035Y-232164D01*
X567035D01*
X566535Y-231664D01*
Y-230664D01*
X567035Y-230164D01*
X80315Y-37158D02*
Y-39658D01*
X80815Y-40157D01*
X81814D01*
X82314Y-39658D01*
Y-37158D01*
X83314Y-39658D02*
X83814Y-40157D01*
X84813D01*
X85313Y-39658D01*
Y-37658D01*
X84813Y-37158D01*
X83814D01*
X83314Y-37658D01*
Y-38158D01*
X83814Y-38658D01*
X85313D01*
X545033Y-320472D02*
X547532D01*
X548032Y-319973D01*
Y-318973D01*
X547532Y-318473D01*
X545033D01*
Y-315474D02*
Y-317473D01*
X546532D01*
X546032Y-316474D01*
Y-315974D01*
X546532Y-315474D01*
X547532D01*
X548032Y-315974D01*
Y-316974D01*
X547532Y-317473D01*
X556731Y-150527D02*
X559231D01*
X559730Y-150027D01*
Y-149027D01*
X559231Y-148527D01*
X556731D01*
X559730Y-145528D02*
Y-147528D01*
X557731Y-145528D01*
X557231D01*
X556731Y-146028D01*
Y-147028D01*
X557231Y-147528D01*
X591732Y-197788D02*
Y-200288D01*
X592232Y-200787D01*
X593232D01*
X593732Y-200288D01*
Y-197788D01*
X594731Y-200787D02*
X595731D01*
X595231D01*
Y-197788D01*
X594731Y-198288D01*
X77756Y-240158D02*
X74757D01*
Y-238658D01*
X75257Y-238158D01*
X76256D01*
X76756Y-238658D01*
Y-240158D01*
Y-239158D02*
X77756Y-238158D01*
X75257Y-237158D02*
X74757Y-236659D01*
Y-235659D01*
X75257Y-235159D01*
X75757D01*
X76256Y-235659D01*
Y-236159D01*
Y-235659D01*
X76756Y-235159D01*
X77256D01*
X77756Y-235659D01*
Y-236659D01*
X77256Y-237158D01*
X75257Y-234159D02*
X74757Y-233660D01*
Y-232660D01*
X75257Y-232160D01*
X77256D01*
X77756Y-232660D01*
Y-233660D01*
X77256Y-234159D01*
X75257D01*
X84646Y-240158D02*
X81647D01*
Y-238658D01*
X82147Y-238158D01*
X83146D01*
X83646Y-238658D01*
Y-240158D01*
Y-239158D02*
X84646Y-238158D01*
Y-235159D02*
Y-237158D01*
X82646Y-235159D01*
X82147D01*
X81647Y-235659D01*
Y-236659D01*
X82147Y-237158D01*
X84146Y-234159D02*
X84646Y-233660D01*
Y-232660D01*
X84146Y-232160D01*
X82147D01*
X81647Y-232660D01*
Y-233660D01*
X82147Y-234159D01*
X82646D01*
X83146Y-233660D01*
Y-232160D01*
X54855Y-258220D02*
Y-255221D01*
X56355D01*
X56855Y-255721D01*
Y-256720D01*
X56355Y-257220D01*
X54855D01*
X55855D02*
X56855Y-258220D01*
X59854D02*
X57854D01*
X59854Y-256221D01*
Y-255721D01*
X59354Y-255221D01*
X58354D01*
X57854Y-255721D01*
X60853D02*
X61353Y-255221D01*
X62353D01*
X62853Y-255721D01*
Y-256221D01*
X62353Y-256720D01*
X62853Y-257220D01*
Y-257720D01*
X62353Y-258220D01*
X61353D01*
X60853Y-257720D01*
Y-257220D01*
X61353Y-256720D01*
X60853Y-256221D01*
Y-255721D01*
X61353Y-256720D02*
X62353D01*
X138390Y-351095D02*
Y-354094D01*
X136891D01*
X136391Y-353594D01*
Y-352594D01*
X136891Y-352095D01*
X138390D01*
X137390D02*
X136391Y-351095D01*
X133392D02*
X135391D01*
X133392Y-353094D01*
Y-353594D01*
X133892Y-354094D01*
X134891D01*
X135391Y-353594D01*
X130893Y-351095D02*
Y-354094D01*
X132392Y-352594D01*
X130393D01*
X138090Y-346464D02*
Y-349463D01*
X136591D01*
X136091Y-348963D01*
Y-347964D01*
X136591Y-347464D01*
X138090D01*
X137091D02*
X136091Y-346464D01*
X133092D02*
X135091D01*
X133092Y-348464D01*
Y-348963D01*
X133592Y-349463D01*
X134591D01*
X135091Y-348963D01*
X132092D02*
X131592Y-349463D01*
X130593D01*
X130093Y-348963D01*
Y-348464D01*
X130593Y-347964D01*
X131093D01*
X130593D01*
X130093Y-347464D01*
Y-346964D01*
X130593Y-346464D01*
X131592D01*
X132092Y-346964D01*
X109252Y-259695D02*
Y-256696D01*
X110751D01*
X111251Y-257195D01*
Y-258195D01*
X110751Y-258695D01*
X109252D01*
X110252D02*
X111251Y-259695D01*
X114250D02*
X112251D01*
X114250Y-257695D01*
Y-257195D01*
X113751Y-256696D01*
X112751D01*
X112251Y-257195D01*
X117249Y-259695D02*
X115250D01*
X117249Y-257695D01*
Y-257195D01*
X116750Y-256696D01*
X115750D01*
X115250Y-257195D01*
X642913Y-337992D02*
X645912D01*
Y-339492D01*
X645413Y-339991D01*
X644413D01*
X643913Y-339492D01*
Y-337992D01*
Y-338992D02*
X642913Y-339991D01*
Y-342990D02*
Y-340991D01*
X644913Y-342990D01*
X645413D01*
X645912Y-342491D01*
Y-341491D01*
X645413Y-340991D01*
X642913Y-343990D02*
Y-344990D01*
Y-344490D01*
X645912D01*
X645413Y-343990D01*
X661417Y-337795D02*
X664416D01*
Y-339295D01*
X663916Y-339795D01*
X662917D01*
X662417Y-339295D01*
Y-337795D01*
Y-338795D02*
X661417Y-339795D01*
Y-342794D02*
Y-340794D01*
X663417Y-342794D01*
X663916D01*
X664416Y-342294D01*
Y-341294D01*
X663916Y-340794D01*
Y-343793D02*
X664416Y-344293D01*
Y-345293D01*
X663916Y-345793D01*
X661917D01*
X661417Y-345293D01*
Y-344293D01*
X661917Y-343793D01*
X663916D01*
X531102Y-342520D02*
Y-339521D01*
X532602D01*
X533102Y-340020D01*
Y-341020D01*
X532602Y-341520D01*
X531102D01*
X532102D02*
X533102Y-342520D01*
X534101D02*
X535101D01*
X534601D01*
Y-339521D01*
X534101Y-340020D01*
X536601Y-342020D02*
X537100Y-342520D01*
X538100D01*
X538600Y-342020D01*
Y-340020D01*
X538100Y-339521D01*
X537100D01*
X536601Y-340020D01*
Y-340520D01*
X537100Y-341020D01*
X538600D01*
X533858Y-327165D02*
Y-324166D01*
X535358D01*
X535858Y-324666D01*
Y-325666D01*
X535358Y-326166D01*
X533858D01*
X534858D02*
X535858Y-327165D01*
X536857D02*
X537857D01*
X537357D01*
Y-324166D01*
X536857Y-324666D01*
X539357D02*
X539856Y-324166D01*
X540856D01*
X541356Y-324666D01*
Y-325166D01*
X540856Y-325666D01*
X541356Y-326166D01*
Y-326665D01*
X540856Y-327165D01*
X539856D01*
X539357Y-326665D01*
Y-326166D01*
X539856Y-325666D01*
X539357Y-325166D01*
Y-324666D01*
X539856Y-325666D02*
X540856D01*
X593299Y-239476D02*
X596298D01*
Y-240976D01*
X595798Y-241476D01*
X594799D01*
X594299Y-240976D01*
Y-239476D01*
Y-240476D02*
X593299Y-241476D01*
X593799Y-242475D02*
X593299Y-242975D01*
Y-243975D01*
X593799Y-244475D01*
X595798D01*
X596298Y-243975D01*
Y-242975D01*
X595798Y-242475D01*
X595299D01*
X594799Y-242975D01*
Y-244475D01*
X646063Y-199213D02*
X649062D01*
Y-200712D01*
X648562Y-201212D01*
X647563D01*
X647063Y-200712D01*
Y-199213D01*
Y-200212D02*
X646063Y-201212D01*
X648562Y-202212D02*
X649062Y-202712D01*
Y-203711D01*
X648562Y-204211D01*
X648062D01*
X647563Y-203711D01*
X647063Y-204211D01*
X646563D01*
X646063Y-203711D01*
Y-202712D01*
X646563Y-202212D01*
X647063D01*
X647563Y-202712D01*
X648062Y-202212D01*
X648562D01*
X647563Y-202712D02*
Y-203711D01*
X575591Y-130709D02*
X578590D01*
Y-132208D01*
X578090Y-132708D01*
X577090D01*
X576590Y-132208D01*
Y-130709D01*
Y-131708D02*
X575591Y-132708D01*
X578590Y-133708D02*
Y-135707D01*
X578090D01*
X576090Y-133708D01*
X575591D01*
X604331Y-238189D02*
Y-235190D01*
X605830D01*
X606330Y-235690D01*
Y-236689D01*
X605830Y-237189D01*
X604331D01*
X605330D02*
X606330Y-238189D01*
X609329Y-235190D02*
X608329Y-235690D01*
X607330Y-236689D01*
Y-237689D01*
X607830Y-238189D01*
X608829D01*
X609329Y-237689D01*
Y-237189D01*
X608829Y-236689D01*
X607330D01*
X614567Y-246457D02*
Y-243458D01*
X616066D01*
X616566Y-243957D01*
Y-244957D01*
X616066Y-245457D01*
X614567D01*
X615567D02*
X616566Y-246457D01*
X619066D02*
Y-243458D01*
X617566Y-244957D01*
X619565D01*
X542840Y-204200D02*
Y-201201D01*
X544340D01*
X544840Y-201700D01*
Y-202700D01*
X544340Y-203200D01*
X542840D01*
X543840D02*
X544840Y-204200D01*
X545839Y-201700D02*
X546339Y-201201D01*
X547339D01*
X547839Y-201700D01*
Y-202200D01*
X547339Y-202700D01*
X546839D01*
X547339D01*
X547839Y-203200D01*
Y-203700D01*
X547339Y-204200D01*
X546339D01*
X545839Y-203700D01*
X542447Y-208530D02*
Y-205531D01*
X543946D01*
X544446Y-206031D01*
Y-207031D01*
X543946Y-207531D01*
X542447D01*
X543446D02*
X544446Y-208530D01*
X547445D02*
X545446D01*
X547445Y-206531D01*
Y-206031D01*
X546945Y-205531D01*
X545946D01*
X545446Y-206031D01*
X692520Y-323622D02*
Y-320623D01*
X694019D01*
X694519Y-321123D01*
Y-322123D01*
X694019Y-322622D01*
X692520D01*
X693519D02*
X694519Y-323622D01*
X695519D02*
X696518D01*
X696019D01*
Y-320623D01*
X695519Y-321123D01*
X630952Y-286221D02*
X627953D01*
Y-288220D01*
Y-291219D02*
Y-289219D01*
X629952Y-291219D01*
X630452D01*
X630952Y-290719D01*
Y-289719D01*
X630452Y-289219D01*
X635283Y-224016D02*
X632283D01*
Y-226015D01*
Y-227015D02*
Y-228014D01*
Y-227515D01*
X635283D01*
X634783Y-227015D01*
X592157Y-153300D02*
X590158D01*
Y-154800D01*
X591157D01*
X590158D01*
Y-156299D01*
X593156D02*
X594156D01*
X593656D01*
Y-153300D01*
X593156Y-153800D01*
X-22684Y-126969D02*
X-19685D01*
Y-125469D01*
X-20185Y-124969D01*
X-22184D01*
X-22684Y-125469D01*
Y-126969D01*
X-19685Y-123969D02*
Y-122970D01*
Y-123470D01*
X-22684D01*
X-22184Y-123969D01*
X-19685Y-119971D02*
X-22684D01*
X-21185Y-121470D01*
Y-119471D01*
X-22684Y-83661D02*
X-19685D01*
Y-82162D01*
X-20185Y-81662D01*
X-22184D01*
X-22684Y-82162D01*
Y-83661D01*
X-19685Y-80662D02*
Y-79663D01*
Y-80163D01*
X-22684D01*
X-22184Y-80662D01*
Y-78163D02*
X-22684Y-77663D01*
Y-76664D01*
X-22184Y-76164D01*
X-21684D01*
X-21185Y-76664D01*
Y-77163D01*
Y-76664D01*
X-20685Y-76164D01*
X-20185D01*
X-19685Y-76664D01*
Y-77663D01*
X-20185Y-78163D01*
X45229Y-18701D02*
X48228D01*
Y-17201D01*
X47728Y-16701D01*
X45729D01*
X45229Y-17201D01*
Y-18701D01*
X48228Y-15702D02*
Y-14702D01*
Y-15202D01*
X45229D01*
X45729Y-15702D01*
X48228Y-13203D02*
Y-12203D01*
Y-12703D01*
X45229D01*
X45729Y-13203D01*
X634646Y-313536D02*
Y-316535D01*
X636145D01*
X636645Y-316036D01*
Y-314036D01*
X636145Y-313536D01*
X634646D01*
X637645Y-314036D02*
X638144Y-313536D01*
X639144D01*
X639644Y-314036D01*
Y-314536D01*
X639144Y-315036D01*
X639644Y-315536D01*
Y-316036D01*
X639144Y-316535D01*
X638144D01*
X637645Y-316036D01*
Y-315536D01*
X638144Y-315036D01*
X637645Y-314536D01*
Y-314036D01*
X638144Y-315036D02*
X639144D01*
X653937Y-313930D02*
Y-316929D01*
X655437D01*
X655936Y-316429D01*
Y-314430D01*
X655437Y-313930D01*
X653937D01*
X656936D02*
X658935D01*
Y-314430D01*
X656936Y-316429D01*
Y-316929D01*
X507087Y-340308D02*
Y-343307D01*
X508586D01*
X509086Y-342807D01*
Y-340808D01*
X508586Y-340308D01*
X507087D01*
X512085D02*
X511085Y-340808D01*
X510086Y-341808D01*
Y-342807D01*
X510585Y-343307D01*
X511585D01*
X512085Y-342807D01*
Y-342307D01*
X511585Y-341808D01*
X510086D01*
X506299Y-324560D02*
Y-327559D01*
X507799D01*
X508299Y-327059D01*
Y-325060D01*
X507799Y-324560D01*
X506299D01*
X511298D02*
X509298D01*
Y-326060D01*
X510298Y-325560D01*
X510798D01*
X511298Y-326060D01*
Y-327059D01*
X510798Y-327559D01*
X509798D01*
X509298Y-327059D01*
X667717Y-328103D02*
Y-331102D01*
X669216D01*
X669716Y-330603D01*
Y-328603D01*
X669216Y-328103D01*
X667717D01*
X672215Y-331102D02*
Y-328103D01*
X670716Y-329603D01*
X672715D01*
X340808Y-98394D02*
X340308Y-98894D01*
Y-99894D01*
X340808Y-100394D01*
X342807D01*
X343307Y-99894D01*
Y-98894D01*
X342807Y-98394D01*
X340308Y-95395D02*
X340808Y-96395D01*
X341808Y-97395D01*
X342807D01*
X343307Y-96895D01*
Y-95895D01*
X342807Y-95395D01*
X342307D01*
X341808Y-95895D01*
Y-97395D01*
X340808Y-94396D02*
X340308Y-93896D01*
Y-92896D01*
X340808Y-92396D01*
X341308D01*
X341808Y-92896D01*
Y-93396D01*
Y-92896D01*
X342307Y-92396D01*
X342807D01*
X343307Y-92896D01*
Y-93896D01*
X342807Y-94396D01*
X367066Y-94519D02*
X367566Y-94019D01*
Y-93019D01*
X367066Y-92520D01*
X365067D01*
X364567Y-93019D01*
Y-94019D01*
X365067Y-94519D01*
X367566Y-97518D02*
X367066Y-96518D01*
X366066Y-95519D01*
X365067D01*
X364567Y-96019D01*
Y-97018D01*
X365067Y-97518D01*
X365567D01*
X366066Y-97018D01*
Y-95519D01*
X364567Y-100517D02*
Y-98518D01*
X366566Y-100517D01*
X367066D01*
X367566Y-100017D01*
Y-99018D01*
X367066Y-98518D01*
X109705Y-98246D02*
X109206Y-98746D01*
Y-99746D01*
X109705Y-100246D01*
X111705D01*
X112205Y-99746D01*
Y-98746D01*
X111705Y-98246D01*
X109206Y-95247D02*
X109705Y-96247D01*
X110705Y-97247D01*
X111705D01*
X112205Y-96747D01*
Y-95747D01*
X111705Y-95247D01*
X111205D01*
X110705Y-95747D01*
Y-97247D01*
X112205Y-94248D02*
Y-93248D01*
Y-93748D01*
X109206D01*
X109705Y-94248D01*
X104784Y-98246D02*
X104284Y-98746D01*
Y-99746D01*
X104784Y-100246D01*
X106784D01*
X107283Y-99746D01*
Y-98746D01*
X106784Y-98246D01*
X104284Y-95247D02*
X104784Y-96247D01*
X105784Y-97247D01*
X106784D01*
X107283Y-96747D01*
Y-95747D01*
X106784Y-95247D01*
X106284D01*
X105784Y-95747D01*
Y-97247D01*
X104784Y-94248D02*
X104284Y-93748D01*
Y-92748D01*
X104784Y-92248D01*
X106784D01*
X107283Y-92748D01*
Y-93748D01*
X106784Y-94248D01*
X104784D01*
X116595Y-91357D02*
X116095Y-91856D01*
Y-92856D01*
X116595Y-93356D01*
X118595D01*
X119095Y-92856D01*
Y-91856D01*
X118595Y-91357D01*
X116095Y-88358D02*
Y-90357D01*
X117595D01*
X117095Y-89357D01*
Y-88857D01*
X117595Y-88358D01*
X118595D01*
X119095Y-88857D01*
Y-89857D01*
X118595Y-90357D01*
Y-87358D02*
X119095Y-86858D01*
Y-85858D01*
X118595Y-85359D01*
X116595D01*
X116095Y-85858D01*
Y-86858D01*
X116595Y-87358D01*
X117095D01*
X117595Y-86858D01*
Y-85359D01*
X123485Y-91357D02*
X122985Y-91856D01*
Y-92856D01*
X123485Y-93356D01*
X125484D01*
X125984Y-92856D01*
Y-91856D01*
X125484Y-91357D01*
X122985Y-88358D02*
Y-90357D01*
X124485D01*
X123985Y-89357D01*
Y-88857D01*
X124485Y-88358D01*
X125484D01*
X125984Y-88857D01*
Y-89857D01*
X125484Y-90357D01*
X123485Y-87358D02*
X122985Y-86858D01*
Y-85858D01*
X123485Y-85359D01*
X123985D01*
X124485Y-85858D01*
X124985Y-85359D01*
X125484D01*
X125984Y-85858D01*
Y-86858D01*
X125484Y-87358D01*
X124985D01*
X124485Y-86858D01*
X123985Y-87358D01*
X123485D01*
X124485Y-86858D02*
Y-85858D01*
X651712Y-232708D02*
X652212Y-232208D01*
Y-231208D01*
X651712Y-230709D01*
X649712D01*
X649213Y-231208D01*
Y-232208D01*
X649712Y-232708D01*
X649213Y-235707D02*
Y-233708D01*
X651212Y-235707D01*
X651712D01*
X652212Y-235207D01*
Y-234208D01*
X651712Y-233708D01*
X649213Y-238706D02*
Y-236707D01*
X651212Y-238706D01*
X651712D01*
X652212Y-238206D01*
Y-237207D01*
X651712Y-236707D01*
X644625Y-232708D02*
X645125Y-232208D01*
Y-231208D01*
X644625Y-230709D01*
X642626D01*
X642126Y-231208D01*
Y-232208D01*
X642626Y-232708D01*
X642126Y-235707D02*
Y-233708D01*
X644125Y-235707D01*
X644625D01*
X645125Y-235207D01*
Y-234208D01*
X644625Y-233708D01*
X642126Y-236707D02*
Y-237706D01*
Y-237207D01*
X645125D01*
X644625Y-236707D01*
X541905Y-132355D02*
X541405Y-131855D01*
X540405D01*
X539906Y-132355D01*
Y-134354D01*
X540405Y-134854D01*
X541405D01*
X541905Y-134354D01*
X544904Y-134854D02*
X542905D01*
X544904Y-132855D01*
Y-132355D01*
X544404Y-131855D01*
X543404D01*
X542905Y-132355D01*
X545904D02*
X546403Y-131855D01*
X547403D01*
X547903Y-132355D01*
Y-134354D01*
X547403Y-134854D01*
X546403D01*
X545904Y-134354D01*
Y-132355D01*
X536371Y-148700D02*
X536871Y-149200D01*
X537870D01*
X538370Y-148700D01*
Y-146701D01*
X537870Y-146201D01*
X536871D01*
X536371Y-146701D01*
X535371Y-146201D02*
X534371D01*
X534871D01*
Y-149200D01*
X535371Y-148700D01*
X532872Y-146701D02*
X532372Y-146201D01*
X531372D01*
X530872Y-146701D01*
Y-148700D01*
X531372Y-149200D01*
X532372D01*
X532872Y-148700D01*
Y-148200D01*
X532372Y-147700D01*
X530872D01*
X683208Y-197275D02*
X683708Y-196775D01*
Y-195775D01*
X683208Y-195276D01*
X681209D01*
X680709Y-195775D01*
Y-196775D01*
X681209Y-197275D01*
X680709Y-198275D02*
Y-199274D01*
Y-198775D01*
X683708D01*
X683208Y-198275D01*
Y-200774D02*
X683708Y-201274D01*
Y-202273D01*
X683208Y-202773D01*
X682708D01*
X682208Y-202273D01*
X681708Y-202773D01*
X681209D01*
X680709Y-202273D01*
Y-201274D01*
X681209Y-200774D01*
X681708D01*
X682208Y-201274D01*
X682708Y-200774D01*
X683208D01*
X682208Y-201274D02*
Y-202273D01*
X683602Y-174047D02*
X684101Y-173547D01*
Y-172547D01*
X683602Y-172047D01*
X681602D01*
X681102Y-172547D01*
Y-173547D01*
X681602Y-174047D01*
X681102Y-175046D02*
Y-176046D01*
Y-175546D01*
X684101D01*
X683602Y-175046D01*
X684101Y-177545D02*
Y-179545D01*
X683602D01*
X681602Y-177545D01*
X681102D01*
X659705Y-210599D02*
X659206Y-211099D01*
Y-212099D01*
X659705Y-212598D01*
X661705D01*
X662205Y-212099D01*
Y-211099D01*
X661705Y-210599D01*
X662205Y-209599D02*
Y-208600D01*
Y-209100D01*
X659206D01*
X659705Y-209599D01*
X659206Y-205101D02*
X659705Y-206101D01*
X660705Y-207100D01*
X661705D01*
X662205Y-206600D01*
Y-205601D01*
X661705Y-205101D01*
X661205D01*
X660705Y-205601D01*
Y-207100D01*
X678090Y-197275D02*
X678590Y-196775D01*
Y-195775D01*
X678090Y-195276D01*
X676090D01*
X675591Y-195775D01*
Y-196775D01*
X676090Y-197275D01*
X675591Y-198275D02*
Y-199274D01*
Y-198775D01*
X678590D01*
X678090Y-198275D01*
X678590Y-202773D02*
Y-200774D01*
X677090D01*
X677590Y-201774D01*
Y-202273D01*
X677090Y-202773D01*
X676090D01*
X675591Y-202273D01*
Y-201274D01*
X676090Y-200774D01*
X663686Y-173688D02*
X663187Y-174188D01*
Y-175188D01*
X663686Y-175688D01*
X665686D01*
X666186Y-175188D01*
Y-174188D01*
X665686Y-173688D01*
X666186Y-172689D02*
Y-171689D01*
Y-172189D01*
X663187D01*
X663686Y-172689D01*
X666186Y-168690D02*
X663187D01*
X664686Y-170189D01*
Y-168190D01*
X676515Y-168535D02*
X677015Y-168035D01*
Y-167035D01*
X676515Y-166535D01*
X674516D01*
X674016Y-167035D01*
Y-168035D01*
X674516Y-168535D01*
X674016Y-169535D02*
Y-170534D01*
Y-170034D01*
X677015D01*
X676515Y-169535D01*
Y-172034D02*
X677015Y-172534D01*
Y-173533D01*
X676515Y-174033D01*
X676015D01*
X675515Y-173533D01*
Y-173033D01*
Y-173533D01*
X675015Y-174033D01*
X674516D01*
X674016Y-173533D01*
Y-172534D01*
X674516Y-172034D01*
X587932Y-174834D02*
X588432Y-174334D01*
Y-173335D01*
X587932Y-172835D01*
X585933D01*
X585433Y-173335D01*
Y-174334D01*
X585933Y-174834D01*
X585433Y-175834D02*
Y-176833D01*
Y-176333D01*
X588432D01*
X587932Y-175834D01*
X585433Y-180332D02*
Y-178333D01*
X587432Y-180332D01*
X587932D01*
X588432Y-179832D01*
Y-178833D01*
X587932Y-178333D01*
X596987Y-175621D02*
X597487Y-175122D01*
Y-174122D01*
X596987Y-173622D01*
X594988D01*
X594488Y-174122D01*
Y-175122D01*
X594988Y-175621D01*
X594488Y-176621D02*
Y-177621D01*
Y-177121D01*
X597487D01*
X596987Y-176621D01*
X594488Y-179120D02*
Y-180120D01*
Y-179620D01*
X597487D01*
X596987Y-179120D01*
X636251Y-192383D02*
X635751Y-191883D01*
X634752D01*
X634252Y-192383D01*
Y-194382D01*
X634752Y-194882D01*
X635751D01*
X636251Y-194382D01*
X637251Y-194882D02*
X638251D01*
X637751D01*
Y-191883D01*
X637251Y-192383D01*
X639750D02*
X640250Y-191883D01*
X641250D01*
X641749Y-192383D01*
Y-194382D01*
X641250Y-194882D01*
X640250D01*
X639750Y-194382D01*
Y-192383D01*
X598288Y-254300D02*
X597788Y-254800D01*
Y-255799D01*
X598288Y-256299D01*
X600288D01*
X600787Y-255799D01*
Y-254800D01*
X600288Y-254300D01*
Y-253300D02*
X600787Y-252800D01*
Y-251801D01*
X600288Y-251301D01*
X598288D01*
X597788Y-251801D01*
Y-252800D01*
X598288Y-253300D01*
X598788D01*
X599288Y-252800D01*
Y-251301D01*
X561161Y-192157D02*
X561660Y-191657D01*
Y-190657D01*
X561161Y-190157D01*
X559161D01*
X558661Y-190657D01*
Y-191657D01*
X559161Y-192157D01*
X561161Y-193157D02*
X561660Y-193656D01*
Y-194656D01*
X561161Y-195156D01*
X560661D01*
X560161Y-194656D01*
X559661Y-195156D01*
X559161D01*
X558661Y-194656D01*
Y-193656D01*
X559161Y-193157D01*
X559661D01*
X560161Y-193656D01*
X560661Y-193157D01*
X561161D01*
X560161Y-193656D02*
Y-194656D01*
X577528Y-238720D02*
X578028Y-239219D01*
X579028D01*
X579528Y-238720D01*
Y-236720D01*
X579028Y-236221D01*
X578028D01*
X577528Y-236720D01*
X576529Y-239219D02*
X574529D01*
Y-238720D01*
X576529Y-236720D01*
Y-236221D01*
X562068Y-228709D02*
X561568Y-229209D01*
Y-230209D01*
X562068Y-230709D01*
X564067D01*
X564567Y-230209D01*
Y-229209D01*
X564067Y-228709D01*
X561568Y-225710D02*
X562068Y-226710D01*
X563067Y-227710D01*
X564067D01*
X564567Y-227210D01*
Y-226210D01*
X564067Y-225710D01*
X563567D01*
X563067Y-226210D01*
Y-227710D01*
X555255Y-230739D02*
X555755Y-230240D01*
Y-229240D01*
X555255Y-228740D01*
X553256D01*
X552756Y-229240D01*
Y-230240D01*
X553256Y-230739D01*
X555755Y-233738D02*
Y-231739D01*
X554255D01*
X554755Y-232739D01*
Y-233239D01*
X554255Y-233738D01*
X553256D01*
X552756Y-233239D01*
Y-232239D01*
X553256Y-231739D01*
X561055Y-232147D02*
X560555Y-231647D01*
X559555D01*
X559055Y-232147D01*
Y-234146D01*
X559555Y-234646D01*
X560555D01*
X561055Y-234146D01*
X563554Y-234646D02*
Y-231647D01*
X562054Y-233146D01*
X564053D01*
X623653Y-236871D02*
X623153Y-236371D01*
X622153D01*
X621654Y-236871D01*
Y-238870D01*
X622153Y-239370D01*
X623153D01*
X623653Y-238870D01*
X624653Y-236871D02*
X625152Y-236371D01*
X626152D01*
X626652Y-236871D01*
Y-237371D01*
X626152Y-237871D01*
X625652D01*
X626152D01*
X626652Y-238370D01*
Y-238870D01*
X626152Y-239370D01*
X625152D01*
X624653Y-238870D01*
X569154Y-112174D02*
X568654Y-112674D01*
Y-113673D01*
X569154Y-114173D01*
X571154D01*
X571654Y-113673D01*
Y-112674D01*
X571154Y-112174D01*
X571654Y-109175D02*
Y-111174D01*
X569654Y-109175D01*
X569154D01*
X568654Y-109675D01*
Y-110674D01*
X569154Y-111174D01*
X576241Y-111387D02*
X575741Y-111886D01*
Y-112886D01*
X576241Y-113386D01*
X578240D01*
X578740Y-112886D01*
Y-111886D01*
X578240Y-111387D01*
X578740Y-110387D02*
Y-109387D01*
Y-109887D01*
X575741D01*
X576241Y-110387D01*
D24*
X599055Y939D02*
X595723D01*
Y1772D01*
X599055Y5104D01*
Y5937D01*
Y15937D02*
X597389D01*
X598222D01*
Y10939D01*
X599055Y11772D01*
X527723Y10939D02*
X529389Y11772D01*
X531055Y13438D01*
Y15104D01*
X530222Y15937D01*
X528556D01*
X527723Y15104D01*
Y14271D01*
X528556Y13438D01*
X531055D01*
Y5937D02*
X529389D01*
X530222D01*
Y939D01*
X531055Y1772D01*
X523558Y5937D02*
X526890D01*
X523558Y2605D01*
Y1772D01*
X524391Y939D01*
X526057D01*
X526890Y1772D01*
D25*
X10335Y-63927D02*
D03*
Y-108415D02*
D03*
D26*
X340551Y-56348D02*
D03*
X382874Y-31348D02*
D03*
D27*
X382874Y-71604D02*
D03*
X340551Y-16092D02*
D03*
M02*
